G04 ================== begin FILE IDENTIFICATION RECORD ==================*
G04 Layout Name:  D:/<user>/Wistron_project/16369-sd/gbr/16369-sd.brd*
G04 Film Name:    TSMD*
G04 File Format:  Gerber RS274X*
G04 File Origin:  Cadence Allegro 16.5-S056*
G04 Origin Date:  Wed Mar 29 13:12:49 2017*
G04 *
G04 Layer:  VIA CLASS/PASTEMASK_TOP*
G04 Layer:  PIN/PASTEMASK_TOP*
G04 Layer:  PACKAGE GEOMETRY/PASTEMASK_TOP*
G04 Layer:  DRAWING FORMAT/LAYER_PCB_STORY*
G04 Layer:  DRAWING FORMAT/LAYER_PAST_T*
G04 Layer:  BOARD GEOMETRY/PANEL_OUTLINE*
G04 *
G04 Offset:    (0.00 0.00)*
G04 Mirror:    No*
G04 Mode:      Positive*
G04 Rotation:  0*
G04 FullContactRelief:  No*
G04 UndefLineWidth:     6.00*
G04 ================== end FILE IDENTIFICATION RECORD ====================*
%FSLAX35Y35*MOIN*%
%IR0*IPPOS*OFA0.00000B0.00000*MIA0B0*SFA1.00000B1.00000*%
%AMMACRO56*
4,1,40,.017,-.013,
.017,.013,
.016939,.013695,
.016759,.014368,
.016464,.015,
.016064,.015571,
.015571,.016064,
.015,.016464,
.014368,.016759,
.013695,.016939,
.013,.017,
-.013,.017,
-.013695,.016939,
-.014368,.016759,
-.015,.016464,
-.015571,.016064,
-.016064,.015571,
-.016464,.015,
-.016759,.014368,
-.016939,.013695,
-.017,.013,
-.017,-.013,
-.016939,-.013695,
-.016759,-.014368,
-.016464,-.015,
-.016064,-.015571,
-.015571,-.016064,
-.015,-.016464,
-.014368,-.016759,
-.013695,-.016939,
-.013,-.017,
.013,-.017,
.013695,-.016939,
.014368,-.016759,
.015,-.016464,
.015571,-.016064,
.016064,-.015571,
.016464,-.015,
.016759,-.014368,
.016939,-.013695,
.017,-.013,
0.0*
%
%ADD56MACRO56*%
%AMMACRO39*
4,1,40,.013,.017,
-.013,.017,
-.013695,.016939,
-.014368,.016759,
-.015,.016464,
-.015571,.016064,
-.016064,.015571,
-.016464,.015,
-.016759,.014368,
-.016939,.013695,
-.017,.013,
-.017,-.013,
-.016939,-.013695,
-.016759,-.014368,
-.016464,-.015,
-.016064,-.015571,
-.015571,-.016064,
-.015,-.016464,
-.014368,-.016759,
-.013695,-.016939,
-.013,-.017,
.013,-.017,
.013695,-.016939,
.014368,-.016759,
.015,-.016464,
.015571,-.016064,
.016064,-.015571,
.016464,-.015,
.016759,-.014368,
.016939,-.013695,
.017,-.013,
.017,.013,
.016939,.013695,
.016759,.014368,
.016464,.015,
.016064,.015571,
.015571,.016064,
.015,.016464,
.014368,.016759,
.013695,.016939,
.013,.017,
0.0*
%
%ADD39MACRO39*%
%AMMACRO57*
4,1,40,.008,.009,
.008695,.008939,
.009368,.008759,
.01,.008464,
.010571,.008064,
.011064,.007571,
.011464,.007,
.011759,.006368,
.011939,.005695,
.012,.005,
.012,-.005,
.011939,-.005695,
.011759,-.006368,
.011464,-.007,
.011064,-.007571,
.010571,-.008064,
.01,-.008464,
.009368,-.008759,
.008695,-.008939,
.008,-.009,
-.008,-.009,
-.008695,-.008939,
-.009368,-.008759,
-.01,-.008464,
-.010571,-.008064,
-.011064,-.007571,
-.011464,-.007,
-.011759,-.006368,
-.011939,-.005695,
-.012,-.005,
-.012,.005,
-.011939,.005695,
-.011759,.006368,
-.011464,.007,
-.011064,.007571,
-.010571,.008064,
-.01,.008464,
-.009368,.008759,
-.008695,.008939,
-.008,.009,
.008,.009,
0.0*
%
%ADD57MACRO57*%
%ADD10C,.04*%
%ADD40C,.032*%
%ADD24C,.026*%
%ADD41C,.028*%
%AMMACRO30*
4,1,40,.011,-.007,
.011,.007,
.010939,.007695,
.010759,.008368,
.010464,.009,
.010064,.009571,
.009571,.010064,
.009,.010464,
.008368,.010759,
.007695,.010939,
.007,.011,
-.007,.011,
-.007695,.010939,
-.008368,.010759,
-.009,.010464,
-.009571,.010064,
-.010064,.009571,
-.010464,.009,
-.010759,.008368,
-.010939,.007695,
-.011,.007,
-.011,-.007,
-.010939,-.007695,
-.010759,-.008368,
-.010464,-.009,
-.010064,-.009571,
-.009571,-.010064,
-.009,-.010464,
-.008368,-.010759,
-.007695,-.010939,
-.007,-.011,
.007,-.011,
.007695,-.010939,
.008368,-.010759,
.009,-.010464,
.009571,-.010064,
.010064,-.009571,
.010464,-.009,
.010759,-.008368,
.010939,-.007695,
.011,-.007,
0.0*
%
%ADD30MACRO30*%
%AMMACRO16*
4,1,40,.007,.011,
-.007,.011,
-.007695,.010939,
-.008368,.010759,
-.009,.010464,
-.009571,.010064,
-.010064,.009571,
-.010464,.009,
-.010759,.008368,
-.010939,.007695,
-.011,.007,
-.011,-.007,
-.010939,-.007695,
-.010759,-.008368,
-.010464,-.009,
-.010064,-.009571,
-.009571,-.010064,
-.009,-.010464,
-.008368,-.010759,
-.007695,-.010939,
-.007,-.011,
.007,-.011,
.007695,-.010939,
.008368,-.010759,
.009,-.010464,
.009571,-.010064,
.010064,-.009571,
.010464,-.009,
.010759,-.008368,
.010939,-.007695,
.011,-.007,
.011,.007,
.010939,.007695,
.010759,.008368,
.010464,.009,
.010064,.009571,
.009571,.010064,
.009,.010464,
.008368,.010759,
.007695,.010939,
.007,.011,
0.0*
%
%ADD16MACRO16*%
%AMMACRO33*
4,1,40,-.012,.008,
-.012,-.008,
-.011939,-.008695,
-.011759,-.009368,
-.011464,-.01,
-.011064,-.010571,
-.010571,-.011064,
-.01,-.011464,
-.009368,-.011759,
-.008695,-.011939,
-.008,-.012,
.008,-.012,
.008695,-.011939,
.009368,-.011759,
.01,-.011464,
.010571,-.011064,
.011064,-.010571,
.011464,-.01,
.011759,-.009368,
.011939,-.008695,
.012,-.008,
.012,.008,
.011939,.008695,
.011759,.009368,
.011464,.01,
.011064,.010571,
.010571,.011064,
.01,.011464,
.009368,.011759,
.008695,.011939,
.008,.012,
-.008,.012,
-.008695,.011939,
-.009368,.011759,
-.01,.011464,
-.010571,.011064,
-.011064,.010571,
-.011464,.01,
-.011759,.009368,
-.011939,.008695,
-.012,.008,
0.0*
%
%ADD33MACRO33*%
%AMMACRO23*
4,1,40,.008,.012,
-.008,.012,
-.008695,.011939,
-.009368,.011759,
-.01,.011464,
-.010571,.011064,
-.011064,.010571,
-.011464,.01,
-.011759,.009368,
-.011939,.008695,
-.012,.008,
-.012,-.008,
-.011939,-.008695,
-.011759,-.009368,
-.011464,-.01,
-.011064,-.010571,
-.010571,-.011064,
-.01,-.011464,
-.009368,-.011759,
-.008695,-.011939,
-.008,-.012,
.008,-.012,
.008695,-.011939,
.009368,-.011759,
.01,-.011464,
.010571,-.011064,
.011064,-.010571,
.011464,-.01,
.011759,-.009368,
.011939,-.008695,
.012,-.008,
.012,.008,
.011939,.008695,
.011759,.009368,
.011464,.01,
.011064,.010571,
.010571,.011064,
.01,.011464,
.009368,.011759,
.008695,.011939,
.008,.012,
0.0*
%
%ADD23MACRO23*%
%AMMACRO42*
4,1,40,-.013,-.017,
.013,-.017,
.013695,-.016939,
.014368,-.016759,
.015,-.016464,
.015571,-.016064,
.016064,-.015571,
.016464,-.015,
.016759,-.014368,
.016939,-.013695,
.017,-.013,
.017,.013,
.016939,.013695,
.016759,.014368,
.016464,.015,
.016064,.015571,
.015571,.016064,
.015,.016464,
.014368,.016759,
.013695,.016939,
.013,.017,
-.013,.017,
-.013695,.016939,
-.014368,.016759,
-.015,.016464,
-.015571,.016064,
-.016064,.015571,
-.016464,.015,
-.016759,.014368,
-.016939,.013695,
-.017,.013,
-.017,-.013,
-.016939,-.013695,
-.016759,-.014368,
-.016464,-.015,
-.016064,-.015571,
-.015571,-.016064,
-.015,-.016464,
-.014368,-.016759,
-.013695,-.016939,
-.013,-.017,
0.0*
%
%ADD42MACRO42*%
%AMMACRO52*
4,1,40,-.017,.013,
-.017,-.013,
-.016939,-.013695,
-.016759,-.014368,
-.016464,-.015,
-.016064,-.015571,
-.015571,-.016064,
-.015,-.016464,
-.014368,-.016759,
-.013695,-.016939,
-.013,-.017,
.013,-.017,
.013695,-.016939,
.014368,-.016759,
.015,-.016464,
.015571,-.016064,
.016064,-.015571,
.016464,-.015,
.016759,-.014368,
.016939,-.013695,
.017,-.013,
.017,.013,
.016939,.013695,
.016759,.014368,
.016464,.015,
.016064,.015571,
.015571,.016064,
.015,.016464,
.014368,.016759,
.013695,.016939,
.013,.017,
-.013,.017,
-.013695,.016939,
-.014368,.016759,
-.015,.016464,
-.015571,.016064,
-.016064,.015571,
-.016464,.015,
-.016759,.014368,
-.016939,.013695,
-.017,.013,
0.0*
%
%ADD52MACRO52*%
%AMMACRO44*
4,1,40,.008,.009,
.008695,.008939,
.009368,.008759,
.01,.008464,
.010571,.008064,
.011064,.007571,
.011464,.007,
.011759,.006368,
.011939,.005695,
.012,.005,
.012,-.005,
.011939,-.005695,
.011759,-.006368,
.011464,-.007,
.011064,-.007571,
.010571,-.008064,
.01,-.008464,
.009368,-.008759,
.008695,-.008939,
.008,-.009,
-.008,-.009,
-.008695,-.008939,
-.009368,-.008759,
-.01,-.008464,
-.010571,-.008064,
-.011064,-.007571,
-.011464,-.007,
-.011759,-.006368,
-.011939,-.005695,
-.012,-.005,
-.012,.005,
-.011939,.005695,
-.011759,.006368,
-.011464,.007,
-.011064,.007571,
-.010571,.008064,
-.01,.008464,
-.009368,.008759,
-.008695,.008939,
-.008,.009,
.008,.009,
0.0*
%
%ADD44MACRO44*%
%AMMACRO31*
4,1,40,.011,-.007,
.011,.007,
.010939,.007695,
.010759,.008368,
.010464,.009,
.010064,.009571,
.009571,.010064,
.009,.010464,
.008368,.010759,
.007695,.010939,
.007,.011,
-.007,.011,
-.007695,.010939,
-.008368,.010759,
-.009,.010464,
-.009571,.010064,
-.010064,.009571,
-.010464,.009,
-.010759,.008368,
-.010939,.007695,
-.011,.007,
-.011,-.007,
-.010939,-.007695,
-.010759,-.008368,
-.010464,-.009,
-.010064,-.009571,
-.009571,-.010064,
-.009,-.010464,
-.008368,-.010759,
-.007695,-.010939,
-.007,-.011,
.007,-.011,
.007695,-.010939,
.008368,-.010759,
.009,-.010464,
.009571,-.010064,
.010064,-.009571,
.010464,-.009,
.010759,-.008368,
.010939,-.007695,
.011,-.007,
0.0*
%
%ADD31MACRO31*%
%AMMACRO17*
4,1,40,.007,.011,
-.007,.011,
-.007695,.010939,
-.008368,.010759,
-.009,.010464,
-.009571,.010064,
-.010064,.009571,
-.010464,.009,
-.010759,.008368,
-.010939,.007695,
-.011,.007,
-.011,-.007,
-.010939,-.007695,
-.010759,-.008368,
-.010464,-.009,
-.010064,-.009571,
-.009571,-.010064,
-.009,-.010464,
-.008368,-.010759,
-.007695,-.010939,
-.007,-.011,
.007,-.011,
.007695,-.010939,
.008368,-.010759,
.009,-.010464,
.009571,-.010064,
.010064,-.009571,
.010464,-.009,
.010759,-.008368,
.010939,-.007695,
.011,-.007,
.011,.007,
.010939,.007695,
.010759,.008368,
.010464,.009,
.010064,.009571,
.009571,.010064,
.009,.010464,
.008368,.010759,
.007695,.010939,
.007,.011,
0.0*
%
%ADD17MACRO17*%
%AMMACRO32*
4,1,40,-.012,.008,
-.012,-.008,
-.011939,-.008695,
-.011759,-.009368,
-.011464,-.01,
-.011064,-.010571,
-.010571,-.011064,
-.01,-.011464,
-.009368,-.011759,
-.008695,-.011939,
-.008,-.012,
.008,-.012,
.008695,-.011939,
.009368,-.011759,
.01,-.011464,
.010571,-.011064,
.011064,-.010571,
.011464,-.01,
.011759,-.009368,
.011939,-.008695,
.012,-.008,
.012,.008,
.011939,.008695,
.011759,.009368,
.011464,.01,
.011064,.010571,
.010571,.011064,
.01,.011464,
.009368,.011759,
.008695,.011939,
.008,.012,
-.008,.012,
-.008695,.011939,
-.009368,.011759,
-.01,.011464,
-.010571,.011064,
-.011064,.010571,
-.011464,.01,
-.011759,.009368,
-.011939,.008695,
-.012,.008,
0.0*
%
%ADD32MACRO32*%
%AMMACRO22*
4,1,40,.008,.012,
-.008,.012,
-.008695,.011939,
-.009368,.011759,
-.01,.011464,
-.010571,.011064,
-.011064,.010571,
-.011464,.01,
-.011759,.009368,
-.011939,.008695,
-.012,.008,
-.012,-.008,
-.011939,-.008695,
-.011759,-.009368,
-.011464,-.01,
-.011064,-.010571,
-.010571,-.011064,
-.01,-.011464,
-.009368,-.011759,
-.008695,-.011939,
-.008,-.012,
.008,-.012,
.008695,-.011939,
.009368,-.011759,
.01,-.011464,
.010571,-.011064,
.011064,-.010571,
.011464,-.01,
.011759,-.009368,
.011939,-.008695,
.012,-.008,
.012,.008,
.011939,.008695,
.011759,.009368,
.011464,.01,
.011064,.010571,
.010571,.011064,
.01,.011464,
.009368,.011759,
.008695,.011939,
.008,.012,
0.0*
%
%ADD22MACRO22*%
%AMMACRO43*
4,1,40,-.013,-.017,
.013,-.017,
.013695,-.016939,
.014368,-.016759,
.015,-.016464,
.015571,-.016064,
.016064,-.015571,
.016464,-.015,
.016759,-.014368,
.016939,-.013695,
.017,-.013,
.017,.013,
.016939,.013695,
.016759,.014368,
.016464,.015,
.016064,.015571,
.015571,.016064,
.015,.016464,
.014368,.016759,
.013695,.016939,
.013,.017,
-.013,.017,
-.013695,.016939,
-.014368,.016759,
-.015,.016464,
-.015571,.016064,
-.016064,.015571,
-.016464,.015,
-.016759,.014368,
-.016939,.013695,
-.017,.013,
-.017,-.013,
-.016939,-.013695,
-.016759,-.014368,
-.016464,-.015,
-.016064,-.015571,
-.015571,-.016064,
-.015,-.016464,
-.014368,-.016759,
-.013695,-.016939,
-.013,-.017,
0.0*
%
%ADD43MACRO43*%
%AMMACRO53*
4,1,40,-.017,.013,
-.017,-.013,
-.016939,-.013695,
-.016759,-.014368,
-.016464,-.015,
-.016064,-.015571,
-.015571,-.016064,
-.015,-.016464,
-.014368,-.016759,
-.013695,-.016939,
-.013,-.017,
.013,-.017,
.013695,-.016939,
.014368,-.016759,
.015,-.016464,
.015571,-.016064,
.016064,-.015571,
.016464,-.015,
.016759,-.014368,
.016939,-.013695,
.017,-.013,
.017,.013,
.016939,.013695,
.016759,.014368,
.016464,.015,
.016064,.015571,
.015571,.016064,
.015,.016464,
.014368,.016759,
.013695,.016939,
.013,.017,
-.013,.017,
-.013695,.016939,
-.014368,.016759,
-.015,.016464,
-.015571,.016064,
-.016064,.015571,
-.016464,.015,
-.016759,.014368,
-.016939,.013695,
-.017,.013,
0.0*
%
%ADD53MACRO53*%
%AMMACRO47*
4,1,40,-.008,-.009,
-.008695,-.008939,
-.009368,-.008759,
-.01,-.008464,
-.010571,-.008064,
-.011064,-.007571,
-.011464,-.007,
-.011759,-.006368,
-.011939,-.005695,
-.012,-.005,
-.012,.005,
-.011939,.005695,
-.011759,.006368,
-.011464,.007,
-.011064,.007571,
-.010571,.008064,
-.01,.008464,
-.009368,.008759,
-.008695,.008939,
-.008,.009,
.008,.009,
.008695,.008939,
.009368,.008759,
.01,.008464,
.010571,.008064,
.011064,.007571,
.011464,.007,
.011759,.006368,
.011939,.005695,
.012,.005,
.012,-.005,
.011939,-.005695,
.011759,-.006368,
.011464,-.007,
.011064,-.007571,
.010571,-.008064,
.01,-.008464,
.009368,-.008759,
.008695,-.008939,
.008,-.009,
-.008,-.009,
0.0*
%
%ADD47MACRO47*%
%ADD11R,.102X.134*%
%ADD51R,.04X.022*%
%ADD27R,.015X.012*%
%ADD26R,.022X.04*%
%ADD15R,.06X.012*%
%ADD48R,.012X.06*%
%ADD13R,.06X.014*%
%ADD49R,.02X.063*%
%ADD37R,.012X.036*%
%ADD36R,.061X.051*%
%ADD45R,.05X.065*%
%ADD12R,.024X.063*%
%ADD54R,.045X.055*%
%ADD25R,.048X.016*%
%ADD46R,.055X.045*%
%ADD14R,.016X.048*%
%AMMACRO35*
4,1,40,-.008,-.012,
.008,-.012,
.008695,-.011939,
.009368,-.011759,
.01,-.011464,
.010571,-.011064,
.011064,-.010571,
.011464,-.01,
.011759,-.009368,
.011939,-.008695,
.012,-.008,
.012,.008,
.011939,.008695,
.011759,.009368,
.011464,.01,
.011064,.010571,
.010571,.011064,
.01,.011464,
.009368,.011759,
.008695,.011939,
.008,.012,
-.008,.012,
-.008695,.011939,
-.009368,.011759,
-.01,.011464,
-.010571,.011064,
-.011064,.010571,
-.011464,.01,
-.011759,.009368,
-.011939,.008695,
-.012,.008,
-.012,-.008,
-.011939,-.008695,
-.011759,-.009368,
-.011464,-.01,
-.011064,-.010571,
-.010571,-.011064,
-.01,-.011464,
-.009368,-.011759,
-.008695,-.011939,
-.008,-.012,
0.0*
%
%ADD35MACRO35*%
%AMMACRO21*
4,1,40,.012,-.008,
.012,.008,
.011939,.008695,
.011759,.009368,
.011464,.01,
.011064,.010571,
.010571,.011064,
.01,.011464,
.009368,.011759,
.008695,.011939,
.008,.012,
-.008,.012,
-.008695,.011939,
-.009368,.011759,
-.01,.011464,
-.010571,.011064,
-.011064,.010571,
-.011464,.01,
-.011759,.009368,
-.011939,.008695,
-.012,.008,
-.012,-.008,
-.011939,-.008695,
-.011759,-.009368,
-.011464,-.01,
-.011064,-.010571,
-.010571,-.011064,
-.01,-.011464,
-.009368,-.011759,
-.008695,-.011939,
-.008,-.012,
.008,-.012,
.008695,-.011939,
.009368,-.011759,
.01,-.011464,
.010571,-.011064,
.011064,-.010571,
.011464,-.01,
.011759,-.009368,
.011939,-.008695,
.012,-.008,
0.0*
%
%ADD21MACRO21*%
%AMMACRO18*
4,1,40,-.007,-.011,
.007,-.011,
.007695,-.010939,
.008368,-.010759,
.009,-.010464,
.009571,-.010064,
.010064,-.009571,
.010464,-.009,
.010759,-.008368,
.010939,-.007695,
.011,-.007,
.011,.007,
.010939,.007695,
.010759,.008368,
.010464,.009,
.010064,.009571,
.009571,.010064,
.009,.010464,
.008368,.010759,
.007695,.010939,
.007,.011,
-.007,.011,
-.007695,.010939,
-.008368,.010759,
-.009,.010464,
-.009571,.010064,
-.010064,.009571,
-.010464,.009,
-.010759,.008368,
-.010939,.007695,
-.011,.007,
-.011,-.007,
-.010939,-.007695,
-.010759,-.008368,
-.010464,-.009,
-.010064,-.009571,
-.009571,-.010064,
-.009,-.010464,
-.008368,-.010759,
-.007695,-.010939,
-.007,-.011,
0.0*
%
%ADD18MACRO18*%
%AMMACRO28*
4,1,40,-.011,.007,
-.011,-.007,
-.010939,-.007695,
-.010759,-.008368,
-.010464,-.009,
-.010064,-.009571,
-.009571,-.010064,
-.009,-.010464,
-.008368,-.010759,
-.007695,-.010939,
-.007,-.011,
.007,-.011,
.007695,-.010939,
.008368,-.010759,
.009,-.010464,
.009571,-.010064,
.010064,-.009571,
.010464,-.009,
.010759,-.008368,
.010939,-.007695,
.011,-.007,
.011,.007,
.010939,.007695,
.010759,.008368,
.010464,.009,
.010064,.009571,
.009571,.010064,
.009,.010464,
.008368,.010759,
.007695,.010939,
.007,.011,
-.007,.011,
-.007695,.010939,
-.008368,.010759,
-.009,.010464,
-.009571,.010064,
-.010064,.009571,
-.010464,.009,
-.010759,.008368,
-.010939,.007695,
-.011,.007,
0.0*
%
%ADD28MACRO28*%
%AMMACRO55*
4,1,40,.017,-.013,
.017,.013,
.016939,.013695,
.016759,.014368,
.016464,.015,
.016064,.015571,
.015571,.016064,
.015,.016464,
.014368,.016759,
.013695,.016939,
.013,.017,
-.013,.017,
-.013695,.016939,
-.014368,.016759,
-.015,.016464,
-.015571,.016064,
-.016064,.015571,
-.016464,.015,
-.016759,.014368,
-.016939,.013695,
-.017,.013,
-.017,-.013,
-.016939,-.013695,
-.016759,-.014368,
-.016464,-.015,
-.016064,-.015571,
-.015571,-.016064,
-.015,-.016464,
-.014368,-.016759,
-.013695,-.016939,
-.013,-.017,
.013,-.017,
.013695,-.016939,
.014368,-.016759,
.015,-.016464,
.015571,-.016064,
.016064,-.015571,
.016464,-.015,
.016759,-.014368,
.016939,-.013695,
.017,-.013,
0.0*
%
%ADD55MACRO55*%
%AMMACRO38*
4,1,40,.013,.017,
-.013,.017,
-.013695,.016939,
-.014368,.016759,
-.015,.016464,
-.015571,.016064,
-.016064,.015571,
-.016464,.015,
-.016759,.014368,
-.016939,.013695,
-.017,.013,
-.017,-.013,
-.016939,-.013695,
-.016759,-.014368,
-.016464,-.015,
-.016064,-.015571,
-.015571,-.016064,
-.015,-.016464,
-.014368,-.016759,
-.013695,-.016939,
-.013,-.017,
.013,-.017,
.013695,-.016939,
.014368,-.016759,
.015,-.016464,
.015571,-.016064,
.016064,-.015571,
.016464,-.015,
.016759,-.014368,
.016939,-.013695,
.017,-.013,
.017,.013,
.016939,.013695,
.016759,.014368,
.016464,.015,
.016064,.015571,
.015571,.016064,
.015,.016464,
.014368,.016759,
.013695,.016939,
.013,.017,
0.0*
%
%ADD38MACRO38*%
%AMMACRO58*
4,1,40,-.008,-.009,
-.008695,-.008939,
-.009368,-.008759,
-.01,-.008464,
-.010571,-.008064,
-.011064,-.007571,
-.011464,-.007,
-.011759,-.006368,
-.011939,-.005695,
-.012,-.005,
-.012,.005,
-.011939,.005695,
-.011759,.006368,
-.011464,.007,
-.011064,.007571,
-.010571,.008064,
-.01,.008464,
-.009368,.008759,
-.008695,.008939,
-.008,.009,
.008,.009,
.008695,.008939,
.009368,.008759,
.01,.008464,
.010571,.008064,
.011064,.007571,
.011464,.007,
.011759,.006368,
.011939,.005695,
.012,.005,
.012,-.005,
.011939,-.005695,
.011759,-.006368,
.011464,-.007,
.011064,-.007571,
.010571,-.008064,
.01,-.008464,
.009368,-.008759,
.008695,-.008939,
.008,-.009,
-.008,-.009,
0.0*
%
%ADD58MACRO58*%
%AMMACRO34*
4,1,40,-.008,-.012,
.008,-.012,
.008695,-.011939,
.009368,-.011759,
.01,-.011464,
.010571,-.011064,
.011064,-.010571,
.011464,-.01,
.011759,-.009368,
.011939,-.008695,
.012,-.008,
.012,.008,
.011939,.008695,
.011759,.009368,
.011464,.01,
.011064,.010571,
.010571,.011064,
.01,.011464,
.009368,.011759,
.008695,.011939,
.008,.012,
-.008,.012,
-.008695,.011939,
-.009368,.011759,
-.01,.011464,
-.010571,.011064,
-.011064,.010571,
-.011464,.01,
-.011759,.009368,
-.011939,.008695,
-.012,.008,
-.012,-.008,
-.011939,-.008695,
-.011759,-.009368,
-.011464,-.01,
-.011064,-.010571,
-.010571,-.011064,
-.01,-.011464,
-.009368,-.011759,
-.008695,-.011939,
-.008,-.012,
0.0*
%
%ADD34MACRO34*%
%AMMACRO20*
4,1,40,.012,-.008,
.012,.008,
.011939,.008695,
.011759,.009368,
.011464,.01,
.011064,.010571,
.010571,.011064,
.01,.011464,
.009368,.011759,
.008695,.011939,
.008,.012,
-.008,.012,
-.008695,.011939,
-.009368,.011759,
-.01,.011464,
-.010571,.011064,
-.011064,.010571,
-.011464,.01,
-.011759,.009368,
-.011939,.008695,
-.012,.008,
-.012,-.008,
-.011939,-.008695,
-.011759,-.009368,
-.011464,-.01,
-.011064,-.010571,
-.010571,-.011064,
-.01,-.011464,
-.009368,-.011759,
-.008695,-.011939,
-.008,-.012,
.008,-.012,
.008695,-.011939,
.009368,-.011759,
.01,-.011464,
.010571,-.011064,
.011064,-.010571,
.011464,-.01,
.011759,-.009368,
.011939,-.008695,
.012,-.008,
0.0*
%
%ADD20MACRO20*%
%AMMACRO19*
4,1,40,-.007,-.011,
.007,-.011,
.007695,-.010939,
.008368,-.010759,
.009,-.010464,
.009571,-.010064,
.010064,-.009571,
.010464,-.009,
.010759,-.008368,
.010939,-.007695,
.011,-.007,
.011,.007,
.010939,.007695,
.010759,.008368,
.010464,.009,
.010064,.009571,
.009571,.010064,
.009,.010464,
.008368,.010759,
.007695,.010939,
.007,.011,
-.007,.011,
-.007695,.010939,
-.008368,.010759,
-.009,.010464,
-.009571,.010064,
-.010064,.009571,
-.010464,.009,
-.010759,.008368,
-.010939,.007695,
-.011,.007,
-.011,-.007,
-.010939,-.007695,
-.010759,-.008368,
-.010464,-.009,
-.010064,-.009571,
-.009571,-.010064,
-.009,-.010464,
-.008368,-.010759,
-.007695,-.010939,
-.007,-.011,
0.0*
%
%ADD19MACRO19*%
%AMMACRO29*
4,1,40,-.011,.007,
-.011,-.007,
-.010939,-.007695,
-.010759,-.008368,
-.010464,-.009,
-.010064,-.009571,
-.009571,-.010064,
-.009,-.010464,
-.008368,-.010759,
-.007695,-.010939,
-.007,-.011,
.007,-.011,
.007695,-.010939,
.008368,-.010759,
.009,-.010464,
.009571,-.010064,
.010064,-.009571,
.010464,-.009,
.010759,-.008368,
.010939,-.007695,
.011,-.007,
.011,.007,
.010939,.007695,
.010759,.008368,
.010464,.009,
.010064,.009571,
.009571,.010064,
.009,.010464,
.008368,.010759,
.007695,.010939,
.007,.011,
-.007,.011,
-.007695,.010939,
-.008368,.010759,
-.009,.010464,
-.009571,.010064,
-.010064,.009571,
-.010464,.009,
-.010759,.008368,
-.010939,.007695,
-.011,.007,
0.0*
%
%ADD29MACRO29*%
%ADD59C,.02*%
%ADD60C,.006*%
G75*
%LPD*%
G75*
G54D10*
X-5631Y5915D03*
X-4866Y709193D03*
X12000Y342400D03*
X211700Y17700D03*
X180200Y342500D03*
X489553Y2518D03*
G54D20*
X41000Y48600D03*
X40200Y58800D03*
X59700Y38600D03*
X164900Y48200D03*
X214500Y201900D03*
G54D11*
X23760Y-1772D03*
X208918D03*
G54D21*
X37400Y48600D03*
X36600Y58800D03*
X56100Y38600D03*
X161300Y48200D03*
X210900Y201900D03*
G54D12*
X68819Y6299D03*
X63819D03*
X58819D03*
X53819D03*
X143839D03*
X138839D03*
X133839D03*
X128839D03*
X123839D03*
X118839D03*
X113839D03*
X108839D03*
X83819D03*
X78819D03*
X73819D03*
X178839D03*
X173839D03*
X168839D03*
X163839D03*
X158839D03*
X153839D03*
X148839D03*
G54D30*
X12100Y77200D03*
X23300Y109200D03*
X52400Y175500D03*
X50272Y288472D03*
X98071Y51625D03*
X75604Y83769D03*
X219500Y56600D03*
X192500Y70200D03*
X218300Y39200D03*
X215378Y29305D03*
X209522Y52212D03*
X180800Y108300D03*
X215516Y135785D03*
X223200Y188750D03*
Y196300D03*
X220723Y291345D03*
G54D13*
X69500Y65420D03*
Y67980D03*
Y70540D03*
X47300D03*
Y67980D03*
Y65420D03*
X69500Y73100D03*
Y75660D03*
Y78220D03*
Y80780D03*
Y83340D03*
Y85900D03*
Y88460D03*
Y91020D03*
Y93580D03*
X47300D03*
Y91020D03*
Y88460D03*
Y85900D03*
Y83340D03*
Y80780D03*
Y78220D03*
Y75660D03*
Y73100D03*
X34400Y84340D03*
Y81780D03*
Y79220D03*
Y76660D03*
X21600D03*
Y79220D03*
Y81780D03*
Y84340D03*
X37190Y196840D03*
Y194280D03*
Y191720D03*
Y189160D03*
X21010D03*
Y191720D03*
Y194280D03*
Y196840D03*
X220600Y61420D03*
Y63980D03*
Y66540D03*
Y69100D03*
Y71660D03*
X198400D03*
Y69100D03*
Y66540D03*
Y63980D03*
Y61420D03*
X220600Y74220D03*
Y76780D03*
Y79340D03*
Y81900D03*
Y84460D03*
Y87020D03*
Y89580D03*
X198400D03*
Y87020D03*
Y84460D03*
Y81900D03*
Y79340D03*
Y76780D03*
Y74220D03*
X187400Y83340D03*
Y80780D03*
Y78220D03*
Y75660D03*
X174600D03*
Y78220D03*
Y80780D03*
Y83340D03*
X207590Y195940D03*
Y193380D03*
Y190820D03*
Y188260D03*
X191410D03*
Y190820D03*
Y193380D03*
Y195940D03*
G54D22*
X52600Y27100D03*
X104300Y28500D03*
X197760Y56827D03*
X215800Y107610D03*
X192724Y80830D03*
G54D31*
X12100Y73800D03*
X23300Y105800D03*
X52400Y172100D03*
X50272Y285072D03*
X98071Y48225D03*
X75604Y80369D03*
X219500Y53200D03*
X192500Y66800D03*
X218300Y35800D03*
X215378Y25905D03*
X209522Y48812D03*
X180800Y104900D03*
X215516Y132385D03*
X223200Y185350D03*
Y192900D03*
X220723Y287945D03*
G54D40*
X13200Y187900D03*
X183653Y191058D03*
G54D14*
X47060Y32450D03*
X44500D03*
X41940D03*
Y25950D03*
X47060D03*
X62440Y25750D03*
X65000D03*
X67560D03*
Y32250D03*
X62440D03*
G54D32*
X30742Y103542D03*
X53700Y118300D03*
X49018Y199384D03*
X106000Y51800D03*
X116500Y27400D03*
X214800Y115200D03*
G36*
G01X116364Y96890D02*
G02X116314I-25J-18150D01*
G01Y89940D01*
G03X116364I25J-11200D01*
G01Y96890D01*
G37*
G54D23*
X52600Y23500D03*
X104300Y24900D03*
X197760Y53227D03*
X215800Y104010D03*
X192724Y77230D03*
G54D41*
X10519Y217435D03*
X8392Y207860D03*
X178563Y197014D03*
X178695Y185153D03*
G54D60*
G01X-322688Y-405500D02*
X-321814Y-404625D01*
X-321159Y-403167D01*
X-320722Y-401124D01*
X-321159Y-399375D01*
X-322032Y-398208D01*
X-323561Y-397333D01*
X-329456D01*
Y-414833D01*
X-322251D01*
X-320722Y-413667D01*
X-319849Y-411916D01*
X-319412Y-409875D01*
X-319849Y-407833D01*
X-321159Y-406083D01*
X-322688Y-405500D01*
X-329456D01*
G01X-309991Y-414833D02*
Y-403167D01*
G01Y-405500D02*
X-308899Y-404333D01*
X-307807Y-403458D01*
X-306279Y-403167D01*
X-305188Y-403458D01*
X-303877Y-404333D01*
G01X-294019Y-420083D02*
X-292709Y-420666D01*
X-290962Y-420083D01*
X-289871Y-418917D01*
X-288997Y-417458D01*
X-287688Y-412792D01*
X-284849Y-403167D01*
G01X-291836D02*
X-287688Y-412792D01*
G01X-268441Y-404625D02*
X-269969Y-403458D01*
X-271279Y-403167D01*
X-273026Y-403750D01*
X-274336Y-404916D01*
X-275209Y-406958D01*
X-275428Y-409000D01*
X-275209Y-411042D01*
X-274336Y-412792D01*
X-273026Y-414250D01*
X-271279Y-414833D01*
X-269751Y-414250D01*
X-268441Y-413083D01*
G01X-257709Y-406958D02*
X-250722D01*
X-251377Y-404916D01*
X-252469Y-403750D01*
X-253997Y-403167D01*
X-255526Y-403458D01*
X-256836Y-404333D01*
X-257709Y-406375D01*
X-258146Y-408125D01*
Y-409875D01*
X-257709Y-411625D01*
X-256617Y-413375D01*
X-255307Y-414541D01*
X-253779Y-414833D01*
X-252251Y-414250D01*
X-250722Y-412500D01*
G01X-214631Y-398792D02*
X-215941Y-397916D01*
X-217469Y-397333D01*
X-219216D01*
X-221181Y-398208D01*
X-222709Y-399666D01*
X-223801Y-401417D01*
X-224674Y-404333D01*
X-224893Y-406958D01*
X-224456Y-409583D01*
X-223801Y-411333D01*
X-222491Y-413083D01*
X-220962Y-414250D01*
X-219434Y-414833D01*
X-217906D01*
X-216377Y-414250D01*
X-215067Y-413375D01*
X-213975Y-412209D01*
G01X-198004Y-414833D02*
Y-403167D01*
G01Y-405208D02*
X-198877Y-404042D01*
X-200188Y-403458D01*
X-201716Y-403167D01*
X-203244Y-403750D01*
X-204554Y-404916D01*
X-205428Y-406666D01*
X-205864Y-409000D01*
X-205428Y-411333D01*
X-204554Y-413083D01*
X-203244Y-414250D01*
X-201716Y-414833D01*
X-200188Y-414541D01*
X-198877Y-413667D01*
X-198004Y-412500D01*
G01X-188146Y-414833D02*
Y-403167D01*
G01Y-406083D02*
X-187272Y-404625D01*
X-185962Y-403458D01*
X-184216Y-403167D01*
X-182688Y-403458D01*
X-181377Y-404625D01*
X-180722Y-406666D01*
Y-414833D01*
G01X-171519Y-420083D02*
X-170209Y-420666D01*
X-168462Y-420083D01*
X-167371Y-418917D01*
X-166497Y-417458D01*
X-165188Y-412792D01*
X-162349Y-403167D01*
G01X-169336D02*
X-165188Y-412792D01*
G01X-149434Y-414833D02*
X-150744Y-414541D01*
X-152054Y-413375D01*
X-152928Y-411333D01*
X-153364Y-409000D01*
X-152928Y-406666D01*
X-152054Y-404625D01*
X-150744Y-403458D01*
X-149434Y-403167D01*
X-148124Y-403458D01*
X-146814Y-404625D01*
X-145941Y-406666D01*
X-145722Y-409000D01*
X-145941Y-411333D01*
X-146814Y-413375D01*
X-148124Y-414541D01*
X-149434Y-414833D01*
G01X-135646D02*
Y-403167D01*
G01Y-406083D02*
X-134772Y-404625D01*
X-133462Y-403458D01*
X-131716Y-403167D01*
X-130188Y-403458D01*
X-128877Y-404625D01*
X-128222Y-406666D01*
Y-414833D01*
G01X-101082D02*
Y-397333D01*
X-92786D01*
G01X-95842Y-405791D02*
X-101082D01*
G01X-82491Y-414833D02*
Y-403167D01*
G01Y-405500D02*
X-81399Y-404333D01*
X-80307Y-403458D01*
X-78779Y-403167D01*
X-77688Y-403458D01*
X-76377Y-404333D01*
G01X-61934Y-414833D02*
X-63244Y-414541D01*
X-64554Y-413375D01*
X-65428Y-411333D01*
X-65864Y-409000D01*
X-65428Y-406666D01*
X-64554Y-404625D01*
X-63244Y-403458D01*
X-61934Y-403167D01*
X-60624Y-403458D01*
X-59314Y-404625D01*
X-58441Y-406666D01*
X-58222Y-409000D01*
X-58441Y-411333D01*
X-59314Y-413375D01*
X-60624Y-414541D01*
X-61934Y-414833D01*
G01X-48146D02*
Y-403167D01*
G01Y-406083D02*
X-47272Y-404625D01*
X-45962Y-403458D01*
X-44216Y-403167D01*
X-42688Y-403458D01*
X-41377Y-404625D01*
X-40722Y-406666D01*
Y-414833D01*
G01X-26934Y-397333D02*
Y-414833D01*
G01X-29991Y-403167D02*
X-23877D01*
G01X3699Y-414833D02*
Y-397333D01*
X8939D01*
X10686Y-398208D01*
X11996Y-400250D01*
X12433Y-402583D01*
X11996Y-404916D01*
X10904Y-406666D01*
X8939Y-407542D01*
X3699D01*
G01X29496Y-414833D02*
Y-403167D01*
G01Y-405208D02*
X28623Y-404042D01*
X27312Y-403458D01*
X25784Y-403167D01*
X24256Y-403750D01*
X22946Y-404916D01*
X22072Y-406666D01*
X21636Y-409000D01*
X22072Y-411333D01*
X22946Y-413083D01*
X24256Y-414250D01*
X25784Y-414833D01*
X27312Y-414541D01*
X28623Y-413667D01*
X29496Y-412500D01*
G01X39354Y-414833D02*
Y-403167D01*
G01Y-406083D02*
X40228Y-404625D01*
X41538Y-403458D01*
X43284Y-403167D01*
X44812Y-403458D01*
X46123Y-404625D01*
X46778Y-406666D01*
Y-414833D01*
G01X57291Y-406958D02*
X64278D01*
X63623Y-404916D01*
X62531Y-403750D01*
X61003Y-403167D01*
X59474Y-403458D01*
X58164Y-404333D01*
X57291Y-406375D01*
X56854Y-408125D01*
Y-409875D01*
X57291Y-411625D01*
X58383Y-413375D01*
X59693Y-414541D01*
X61221Y-414833D01*
X62749Y-414250D01*
X64278Y-412500D01*
G01X78066Y-414833D02*
Y-397333D01*
G01X114812Y-405500D02*
X115686Y-404625D01*
X116341Y-403167D01*
X116778Y-401124D01*
X116341Y-399375D01*
X115468Y-398208D01*
X113939Y-397333D01*
X108044D01*
Y-414833D01*
X115249D01*
X116778Y-413667D01*
X117651Y-411916D01*
X118088Y-409875D01*
X117651Y-407833D01*
X116341Y-406083D01*
X114812Y-405500D01*
X108044D01*
G01X130566Y-414833D02*
X129256Y-414541D01*
X127946Y-413375D01*
X127072Y-411333D01*
X126636Y-409000D01*
X127072Y-406666D01*
X127946Y-404625D01*
X129256Y-403458D01*
X130566Y-403167D01*
X131876Y-403458D01*
X133186Y-404625D01*
X134059Y-406666D01*
X134278Y-409000D01*
X134059Y-411333D01*
X133186Y-413375D01*
X131876Y-414541D01*
X130566Y-414833D01*
G01X151996D02*
Y-403167D01*
G01Y-405208D02*
X151123Y-404042D01*
X149812Y-403458D01*
X148284Y-403167D01*
X146756Y-403750D01*
X145446Y-404916D01*
X144572Y-406666D01*
X144136Y-409000D01*
X144572Y-411333D01*
X145446Y-413083D01*
X146756Y-414250D01*
X148284Y-414833D01*
X149812Y-414541D01*
X151123Y-413667D01*
X151996Y-412500D01*
G01X162509Y-414833D02*
Y-403167D01*
G01Y-405500D02*
X163601Y-404333D01*
X164693Y-403458D01*
X166221Y-403167D01*
X167312Y-403458D01*
X168623Y-404333D01*
G01X186996Y-397333D02*
Y-414833D01*
G01Y-412209D02*
X186123Y-413667D01*
X184812Y-414541D01*
X183284Y-414833D01*
X181538Y-414250D01*
X180228Y-412792D01*
X179354Y-411042D01*
X179136Y-409000D01*
X179354Y-406958D01*
X180228Y-405208D01*
X181538Y-403750D01*
X183284Y-403167D01*
X184812Y-403458D01*
X185904Y-404042D01*
X186996Y-405208D01*
G01X-111361Y-369833D02*
Y-352333D01*
X-105684Y-366916D01*
X-100007Y-352333D01*
Y-369833D01*
G01X-88184D02*
X-89494Y-369541D01*
X-90804Y-368375D01*
X-91678Y-366333D01*
X-92114Y-364000D01*
X-91678Y-361666D01*
X-90804Y-359625D01*
X-89494Y-358458D01*
X-88184Y-358167D01*
X-86874Y-358458D01*
X-85564Y-359625D01*
X-84691Y-361666D01*
X-84472Y-364000D01*
X-84691Y-366333D01*
X-85564Y-368375D01*
X-86874Y-369541D01*
X-88184Y-369833D01*
G01X-66754Y-352333D02*
Y-369833D01*
G01Y-367209D02*
X-67627Y-368667D01*
X-68938Y-369541D01*
X-70466Y-369833D01*
X-72212Y-369250D01*
X-73522Y-367792D01*
X-74396Y-366042D01*
X-74614Y-364000D01*
X-74396Y-361958D01*
X-73522Y-360208D01*
X-72212Y-358750D01*
X-70466Y-358167D01*
X-68938Y-358458D01*
X-67846Y-359042D01*
X-66754Y-360208D01*
G01X-56459Y-361958D02*
X-49472D01*
X-50127Y-359916D01*
X-51219Y-358750D01*
X-52747Y-358167D01*
X-54276Y-358458D01*
X-55586Y-359333D01*
X-56459Y-361375D01*
X-56896Y-363125D01*
Y-364875D01*
X-56459Y-366625D01*
X-55367Y-368375D01*
X-54057Y-369541D01*
X-52529Y-369833D01*
X-51001Y-369250D01*
X-49472Y-367500D01*
G01X-35684Y-369833D02*
Y-352333D01*
G01X244916Y-414833D02*
Y-397333D01*
X242296Y-400833D01*
G01Y-414833D02*
X247536D01*
G01X258268Y-407542D02*
X259796Y-405500D01*
X261106Y-404333D01*
X262853Y-403750D01*
X264381Y-404333D01*
X265473Y-405500D01*
X266346Y-407250D01*
X266564Y-409291D01*
X266346Y-411042D01*
X265473Y-412792D01*
X264162Y-414250D01*
X262634Y-414833D01*
X260888Y-414250D01*
X259359Y-412500D01*
X258486Y-409875D01*
X258268Y-406958D01*
X258704Y-403167D01*
X259359Y-401124D01*
X260451Y-399083D01*
X261979Y-397625D01*
X263508Y-397333D01*
X265036Y-397916D01*
X266128Y-399375D01*
G01X275113Y-411333D02*
X276422Y-413375D01*
X278169Y-414541D01*
X280134Y-414833D01*
X281881Y-414541D01*
X283628Y-413083D01*
X284719Y-411333D01*
X284938Y-409583D01*
X284501Y-407542D01*
X282973Y-406083D01*
X281444Y-405500D01*
X279479D01*
G01X281444D02*
X282754Y-404625D01*
X283846Y-403167D01*
X284283Y-401417D01*
X283846Y-399666D01*
X282754Y-398208D01*
X280789Y-397333D01*
X278824Y-397625D01*
X276859Y-398792D01*
G01X293268Y-407542D02*
X294796Y-405500D01*
X296106Y-404333D01*
X297853Y-403750D01*
X299381Y-404333D01*
X300473Y-405500D01*
X301346Y-407250D01*
X301564Y-409291D01*
X301346Y-411042D01*
X300473Y-412792D01*
X299162Y-414250D01*
X297634Y-414833D01*
X295888Y-414250D01*
X294359Y-412500D01*
X293486Y-409875D01*
X293268Y-406958D01*
X293704Y-403167D01*
X294359Y-401124D01*
X295451Y-399083D01*
X296979Y-397625D01*
X298508Y-397333D01*
X300036Y-397916D01*
X301128Y-399375D01*
G01X311204Y-412792D02*
X312733Y-414250D01*
X314479Y-414833D01*
X316226Y-414250D01*
X317754Y-412500D01*
X318846Y-409875D01*
X319283Y-407250D01*
Y-404042D01*
X318846Y-401417D01*
X317754Y-399083D01*
X316444Y-397916D01*
X314916Y-397333D01*
X313169Y-397916D01*
X311859Y-399083D01*
X310986Y-400833D01*
X310549Y-403167D01*
X310986Y-405208D01*
X312078Y-407250D01*
X313388Y-408417D01*
X314916Y-408708D01*
X316662Y-408125D01*
X317973Y-406666D01*
X319283Y-404042D01*
G01X231799Y-369833D02*
Y-352333D01*
X237039D01*
X238786Y-353208D01*
X240096Y-355250D01*
X240533Y-357583D01*
X240096Y-359916D01*
X239004Y-361666D01*
X237039Y-362542D01*
X231799D01*
G01X258469Y-353792D02*
X257159Y-352916D01*
X255631Y-352333D01*
X253884D01*
X251919Y-353208D01*
X250391Y-354666D01*
X249299Y-356417D01*
X248426Y-359333D01*
X248207Y-361958D01*
X248644Y-364583D01*
X249299Y-366333D01*
X250609Y-368083D01*
X252138Y-369250D01*
X253666Y-369833D01*
X255194D01*
X256723Y-369250D01*
X258033Y-368375D01*
X259125Y-367209D01*
G01X272912Y-360500D02*
X273786Y-359625D01*
X274441Y-358167D01*
X274878Y-356124D01*
X274441Y-354375D01*
X273568Y-353208D01*
X272039Y-352333D01*
X266144D01*
Y-369833D01*
X273349D01*
X274878Y-368667D01*
X275751Y-366916D01*
X276188Y-364875D01*
X275751Y-362833D01*
X274441Y-361083D01*
X272912Y-360500D01*
X266144D01*
G01X282116Y-375666D02*
X295216D01*
G01X301144Y-369833D02*
Y-352333D01*
X311188Y-369833D01*
Y-352333D01*
G01X323666Y-369833D02*
X321919Y-369541D01*
X320391Y-368375D01*
X319081Y-366625D01*
X318207Y-364583D01*
X317771Y-362250D01*
Y-359916D01*
X318207Y-357583D01*
X319081Y-355541D01*
X320391Y-353792D01*
X321919Y-352625D01*
X323666Y-352333D01*
X325412Y-352625D01*
X326941Y-353792D01*
X328251Y-355541D01*
X329125Y-357583D01*
X329561Y-359916D01*
Y-362250D01*
X329125Y-364583D01*
X328251Y-366625D01*
X326941Y-368375D01*
X325412Y-369541D01*
X323666Y-369833D01*
G01X374507Y-352333D02*
X379966Y-369833D01*
X385425Y-352333D01*
G01X401833Y-369833D02*
X393099D01*
Y-352333D01*
X401833D01*
G01X398339Y-360791D02*
X393099D01*
G01X410599Y-369833D02*
Y-352333D01*
X416058D01*
X417804Y-353208D01*
X418896Y-354375D01*
X419333Y-356708D01*
X418896Y-359042D01*
X417586Y-360500D01*
X416058Y-361375D01*
X410599D01*
G01X416058D02*
X419333Y-369833D01*
G01X432466Y-370416D02*
X432029Y-370125D01*
Y-369541D01*
X432466Y-369250D01*
X432903Y-369541D01*
Y-370125D01*
X432466Y-370416D01*
G01X392881Y-412500D02*
X394628Y-413958D01*
X396593Y-414833D01*
X398339D01*
X400086Y-413958D01*
X401396Y-412500D01*
X402051Y-410458D01*
X401614Y-408417D01*
X400523Y-406666D01*
X398558Y-405500D01*
X395938Y-404916D01*
X394409Y-403750D01*
X393754Y-401708D01*
X394191Y-399666D01*
X395283Y-398208D01*
X396811Y-397333D01*
X398339D01*
X399868Y-397916D01*
X401178Y-399375D01*
G01X410163Y-414833D02*
Y-397333D01*
X414529D01*
X416276Y-398208D01*
X417586Y-399375D01*
X418678Y-401124D01*
X419551Y-403167D01*
X419769Y-406083D01*
X419551Y-409000D01*
X418678Y-411042D01*
X417586Y-412792D01*
X416276Y-413958D01*
X414529Y-414833D01*
X410163D01*
G01X521166Y-397333D02*
Y-414833D01*
G01X516144Y-397333D02*
X526188D01*
G01X534081Y-412500D02*
X535828Y-413958D01*
X537793Y-414833D01*
X539539D01*
X541286Y-413958D01*
X542596Y-412500D01*
X543251Y-410458D01*
X542814Y-408417D01*
X541723Y-406666D01*
X539758Y-405500D01*
X537138Y-404916D01*
X535609Y-403750D01*
X534954Y-401708D01*
X535391Y-399666D01*
X536483Y-398208D01*
X538011Y-397333D01*
X539539D01*
X541068Y-397916D01*
X542378Y-399375D01*
G01X550489Y-414833D02*
Y-397333D01*
X556166Y-411916D01*
X561843Y-397333D01*
Y-414833D01*
G01X568863D02*
Y-397333D01*
X573229D01*
X574976Y-398208D01*
X576286Y-399375D01*
X577378Y-401124D01*
X578251Y-403167D01*
X578469Y-406083D01*
X578251Y-409000D01*
X577378Y-411042D01*
X576286Y-412792D01*
X574976Y-413958D01*
X573229Y-414833D01*
X568863D01*
G01X508049Y-352333D02*
Y-369833D01*
X516783D01*
G01X533846D02*
Y-358167D01*
G01Y-360208D02*
X532973Y-359042D01*
X531662Y-358458D01*
X530134Y-358167D01*
X528606Y-358750D01*
X527296Y-359916D01*
X526422Y-361666D01*
X525986Y-364000D01*
X526422Y-366333D01*
X527296Y-368083D01*
X528606Y-369250D01*
X530134Y-369833D01*
X531662Y-369541D01*
X532973Y-368667D01*
X533846Y-367500D01*
G01X542831Y-375083D02*
X544141Y-375666D01*
X545888Y-375083D01*
X546979Y-373917D01*
X547853Y-372458D01*
X549162Y-367792D01*
X552001Y-358167D01*
G01X545014D02*
X549162Y-367792D01*
G01X561641Y-361958D02*
X568628D01*
X567973Y-359916D01*
X566881Y-358750D01*
X565353Y-358167D01*
X563824Y-358458D01*
X562514Y-359333D01*
X561641Y-361375D01*
X561204Y-363125D01*
Y-364875D01*
X561641Y-366625D01*
X562733Y-368375D01*
X564043Y-369541D01*
X565571Y-369833D01*
X567099Y-369250D01*
X568628Y-367500D01*
G01X579359Y-369833D02*
Y-358167D01*
G01Y-360500D02*
X580451Y-359333D01*
X581543Y-358458D01*
X583071Y-358167D01*
X584162Y-358458D01*
X585473Y-359333D01*
G01X672466Y-414833D02*
X670719Y-414541D01*
X669191Y-413375D01*
X667881Y-411625D01*
X667007Y-409583D01*
X666571Y-407250D01*
Y-404916D01*
X667007Y-402583D01*
X667881Y-400541D01*
X669191Y-398792D01*
X670719Y-397625D01*
X672466Y-397333D01*
X674212Y-397625D01*
X675741Y-398792D01*
X677051Y-400541D01*
X677925Y-402583D01*
X678361Y-404916D01*
Y-407250D01*
X677925Y-409583D01*
X677051Y-411625D01*
X675741Y-413375D01*
X674212Y-414541D01*
X672466Y-414833D01*
G01X674212Y-410166D02*
X676833Y-414833D01*
G01X685163Y-397333D02*
Y-409875D01*
X686036Y-412500D01*
X687783Y-414250D01*
X689966Y-414833D01*
X692149Y-414250D01*
X693896Y-412500D01*
X694769Y-409875D01*
Y-397333D01*
G01X704846D02*
X710086D01*
G01X707466D02*
Y-414833D01*
G01X704846D02*
X710086D01*
G01X719944D02*
Y-397333D01*
X729988Y-414833D01*
Y-397333D01*
G01X747269Y-398792D02*
X745959Y-397916D01*
X744431Y-397333D01*
X742684D01*
X740719Y-398208D01*
X739191Y-399666D01*
X738099Y-401417D01*
X737226Y-404333D01*
X737007Y-406958D01*
X737444Y-409583D01*
X738099Y-411333D01*
X739409Y-413083D01*
X740938Y-414250D01*
X742466Y-414833D01*
X743994D01*
X745523Y-414250D01*
X746833Y-413375D01*
X747925Y-412209D01*
G01X759966Y-414833D02*
Y-406958D01*
X755599Y-397333D01*
G01X764333D02*
X759966Y-406958D01*
G01X650163Y-369833D02*
Y-352333D01*
X654529D01*
X656276Y-353208D01*
X657586Y-354375D01*
X658678Y-356124D01*
X659551Y-358167D01*
X659769Y-361083D01*
X659551Y-364000D01*
X658678Y-366042D01*
X657586Y-367792D01*
X656276Y-368958D01*
X654529Y-369833D01*
X650163D01*
G01X669191Y-361958D02*
X676178D01*
X675523Y-359916D01*
X674431Y-358750D01*
X672903Y-358167D01*
X671374Y-358458D01*
X670064Y-359333D01*
X669191Y-361375D01*
X668754Y-363125D01*
Y-364875D01*
X669191Y-366625D01*
X670283Y-368375D01*
X671593Y-369541D01*
X673121Y-369833D01*
X674649Y-369250D01*
X676178Y-367500D01*
G01X686691Y-367792D02*
X687783Y-368958D01*
X689311Y-369833D01*
X690621D01*
X691931Y-369250D01*
X692804Y-368375D01*
X693241Y-367209D01*
X693023Y-365458D01*
X692149Y-364583D01*
X688219Y-362833D01*
X687346Y-360791D01*
X687783Y-359333D01*
X688656Y-358458D01*
X689966Y-358167D01*
X691276Y-358458D01*
X692586Y-359333D01*
G01X707466Y-358167D02*
Y-369833D01*
G01Y-353500D02*
X707029Y-353208D01*
Y-352625D01*
X707466Y-352333D01*
X707903Y-352625D01*
Y-353208D01*
X707466Y-353500D01*
G01X721909Y-374208D02*
X723438Y-375375D01*
X725184Y-375666D01*
X726712Y-375375D01*
X728023Y-373917D01*
X728896Y-371875D01*
Y-358167D01*
G01Y-360500D02*
X728023Y-359333D01*
X726712Y-358458D01*
X725184Y-358167D01*
X723438Y-358750D01*
X722346Y-359916D01*
X721472Y-361958D01*
X721036Y-364000D01*
X721254Y-365750D01*
X722128Y-367792D01*
X723438Y-369250D01*
X725184Y-369833D01*
X726494Y-369541D01*
X728023Y-368375D01*
X728896Y-367209D01*
G01X738754Y-369833D02*
Y-358167D01*
G01Y-361083D02*
X739628Y-359625D01*
X740938Y-358458D01*
X742684Y-358167D01*
X744212Y-358458D01*
X745523Y-359625D01*
X746178Y-361666D01*
Y-369833D01*
G01X756691Y-361958D02*
X763678D01*
X763023Y-359916D01*
X761931Y-358750D01*
X760403Y-358167D01*
X758874Y-358458D01*
X757564Y-359333D01*
X756691Y-361375D01*
X756254Y-363125D01*
Y-364875D01*
X756691Y-366625D01*
X757783Y-368375D01*
X759093Y-369541D01*
X760621Y-369833D01*
X762149Y-369250D01*
X763678Y-367500D01*
G01X774409Y-369833D02*
Y-358167D01*
G01Y-360500D02*
X775501Y-359333D01*
X776593Y-358458D01*
X778121Y-358167D01*
X779212Y-358458D01*
X780523Y-359333D01*
G01X821166Y-397333D02*
X819419Y-397916D01*
X818109Y-399375D01*
X817236Y-401124D01*
X816581Y-403458D01*
X816363Y-406083D01*
X816581Y-408708D01*
X817236Y-411042D01*
X818109Y-412792D01*
X819419Y-414250D01*
X821166Y-414833D01*
X822912Y-414250D01*
X824223Y-412792D01*
X825096Y-411042D01*
X825751Y-408708D01*
X825969Y-406083D01*
X825751Y-403458D01*
X825096Y-401124D01*
X824223Y-399375D01*
X822912Y-397916D01*
X821166Y-397333D01*
G01X833863Y-411333D02*
X835172Y-413375D01*
X836919Y-414541D01*
X838884Y-414833D01*
X840631Y-414541D01*
X842378Y-413083D01*
X843469Y-411333D01*
X843688Y-409583D01*
X843251Y-407542D01*
X841723Y-406083D01*
X840194Y-405500D01*
X838229D01*
G01X840194D02*
X841504Y-404625D01*
X842596Y-403167D01*
X843033Y-401417D01*
X842596Y-399666D01*
X841504Y-398208D01*
X839539Y-397333D01*
X837574Y-397625D01*
X835609Y-398792D01*
G01X852236Y-415416D02*
X860096Y-397333D01*
G01X869518Y-400250D02*
X870828Y-398500D01*
X872356Y-397625D01*
X874103Y-397333D01*
X876286Y-397916D01*
X877814Y-399375D01*
X878251Y-401124D01*
X878033Y-402875D01*
X877159Y-404333D01*
X872793Y-407250D01*
X870828Y-409291D01*
X869518Y-412209D01*
X869081Y-414833D01*
X878251D01*
G01X887454Y-412792D02*
X888983Y-414250D01*
X890729Y-414833D01*
X892476Y-414250D01*
X894004Y-412500D01*
X895096Y-409875D01*
X895533Y-407250D01*
Y-404042D01*
X895096Y-401417D01*
X894004Y-399083D01*
X892694Y-397916D01*
X891166Y-397333D01*
X889419Y-397916D01*
X888109Y-399083D01*
X887236Y-400833D01*
X886799Y-403167D01*
X887236Y-405208D01*
X888328Y-407250D01*
X889638Y-408417D01*
X891166Y-408708D01*
X892912Y-408125D01*
X894223Y-406666D01*
X895533Y-404042D01*
G01X904736Y-415416D02*
X912596Y-397333D01*
G01X922018Y-400250D02*
X923328Y-398500D01*
X924856Y-397625D01*
X926603Y-397333D01*
X928786Y-397916D01*
X930314Y-399375D01*
X930751Y-401124D01*
X930533Y-402875D01*
X929659Y-404333D01*
X925293Y-407250D01*
X923328Y-409291D01*
X922018Y-412209D01*
X921581Y-414833D01*
X930751D01*
G01X943666Y-397333D02*
X941919Y-397916D01*
X940609Y-399375D01*
X939736Y-401124D01*
X939081Y-403458D01*
X938863Y-406083D01*
X939081Y-408708D01*
X939736Y-411042D01*
X940609Y-412792D01*
X941919Y-414250D01*
X943666Y-414833D01*
X945412Y-414250D01*
X946723Y-412792D01*
X947596Y-411042D01*
X948251Y-408708D01*
X948469Y-406083D01*
X948251Y-403458D01*
X947596Y-401124D01*
X946723Y-399375D01*
X945412Y-397916D01*
X943666Y-397333D01*
G01X961166Y-414833D02*
Y-397333D01*
X958546Y-400833D01*
G01Y-414833D02*
X963786D01*
G01X978229D02*
X978666Y-411042D01*
X979321Y-407833D01*
X980194Y-404916D01*
X981286Y-401708D01*
X983033Y-397333D01*
X974299D01*
G01X868863Y-369833D02*
Y-352333D01*
X873229D01*
X874976Y-353208D01*
X876286Y-354375D01*
X877378Y-356124D01*
X878251Y-358167D01*
X878469Y-361083D01*
X878251Y-364000D01*
X877378Y-366042D01*
X876286Y-367792D01*
X874976Y-368958D01*
X873229Y-369833D01*
X868863D01*
G01X895096D02*
Y-358167D01*
G01Y-360208D02*
X894223Y-359042D01*
X892912Y-358458D01*
X891384Y-358167D01*
X889856Y-358750D01*
X888546Y-359916D01*
X887672Y-361666D01*
X887236Y-364000D01*
X887672Y-366333D01*
X888546Y-368083D01*
X889856Y-369250D01*
X891384Y-369833D01*
X892912Y-369541D01*
X894223Y-368667D01*
X895096Y-367500D01*
G01X908666Y-352333D02*
Y-369833D01*
G01X905609Y-358167D02*
X911723D01*
G01X922891Y-361958D02*
X929878D01*
X929223Y-359916D01*
X928131Y-358750D01*
X926603Y-358167D01*
X925074Y-358458D01*
X923764Y-359333D01*
X922891Y-361375D01*
X922454Y-363125D01*
Y-364875D01*
X922891Y-366625D01*
X923983Y-368375D01*
X925293Y-369541D01*
X926821Y-369833D01*
X928349Y-369250D01*
X929878Y-367500D01*
G01X-11811Y-26378D02*
G03X-7874Y-22441I0J3937D01*
G01X-31496Y-11378D02*
G03X-16496Y-26378I15000J0D01*
G01X0Y-18504D02*
G03X-7874I-3937J0D01*
G01X-11811Y-26378D02*
X-16496D01*
G01X-31496Y727913D02*
Y-11378D01*
G01X-7874Y-18504D02*
Y-22441D01*
G01Y20866D02*
G03X0I3937J0D01*
G01X-14607Y16741D02*
G03I-4291J0D01*
G01X-7874Y175427D02*
Y20866D01*
G01X-11608Y217029D02*
G03X-19685Y205824I3734J-11205D01*
G01X-9118Y209559D02*
G03X-11811Y205824I1244J-3735D01*
G01X-19685Y187877D02*
G03X-11608Y176672I11811J0D01*
G01X-11811Y187877D02*
G03X-9118Y184142I3937J0D01*
G01X-7874Y175427D02*
X-11609Y176672D01*
G01X-2692Y182000D02*
X-9119Y184142D01*
G01X-7874Y218273D02*
X-11609Y217029D01*
G01X-2692Y211701D02*
X-9119Y209559D01*
G01X-7874Y307086D02*
Y218273D01*
G01X-19685Y205824D02*
Y187877D01*
G01X-11811Y205824D02*
Y187877D01*
G01X0Y370079D02*
G03X-7874I-3937J0D01*
G01Y346456D02*
G03X0I3937J0D01*
G01Y307086D02*
G03X-7874I-3937J0D01*
G01Y370079D02*
Y346456D01*
G01Y409449D02*
G03X0I3937J0D01*
G01X-7874Y564010D02*
Y409449D01*
G01X-11608Y605612D02*
G03X-19685Y594406I3735J-11206D01*
G01X-9118Y598141D02*
G03X-11811Y594406I1244J-3735D01*
G01X-19685Y576459D02*
G03X-11608Y565254I11811J0D01*
G01X-11811Y576459D02*
G03X-9118Y572724I3937J0D01*
G01X-7874Y564010D02*
X-11609Y565255D01*
G01X-2692Y570582D02*
X-9119Y572725D01*
G01X-2692Y600284D02*
X-9119Y598141D01*
G01X-19685Y594406D02*
Y576459D01*
G01X-11811Y594406D02*
Y576459D01*
G01X-7874Y606856D02*
X-11609Y605611D01*
G01X-7874Y695669D02*
Y606856D01*
G01X-13215Y723144D02*
G03I-4291J0D01*
G01X-7874Y738976D02*
G03X-11811Y742913I-3937J0D01*
G01X-16496D02*
G03X-31496Y727913I0J-15000D01*
G01X-7874Y735039D02*
G03X0I3937J0D01*
G01Y695669D02*
G03X-7874I-3937J0D01*
G01X-11811Y742913D02*
X-16496D01*
G01X-7874Y738976D02*
Y735039D01*
G01X29075Y-26378D02*
G03X31044Y-24410I0J1969D01*
G01D02*
Y-788D01*
G01X0Y-22441D02*
G03X3937Y-26378I3937J0D01*
G01X0Y178265D02*
Y-22441D01*
G01X3937Y-26378D02*
X29075D01*
G01X44390Y5118D02*
G03I-2658J0D01*
G01X33012Y1181D02*
G03X31044Y-788I0J-1968D01*
G01X33012Y1181D02*
X199666D01*
G01X71407Y128987D02*
G03X76975Y134555I2784J2784D01*
G01X64567Y137457D02*
G03X65720Y134673I3938J0D01*
G01D02*
X94910Y105484D01*
G01X64567Y137457D02*
Y249131D01*
G01X-2692Y211701D02*
G03X0Y215436I-1245J3735D01*
G01Y178265D02*
G03X-2692Y182000I-3937J0D01*
G01X0Y350394D02*
Y215436D01*
G01X64567Y286302D02*
G03X67259Y282567I3937J0D01*
G01Y252866D02*
G03X64567Y249131I1245J-3735D01*
G01X73686Y280425D02*
X67259Y282567D01*
G01X64567Y286302D02*
Y350394D01*
G01X73686Y255008D02*
X67259Y252866D01*
G01X64567Y346456D02*
G03X72441I3937J0D01*
G01Y321260D02*
G03X64567I-3937J0D01*
G01X29075Y362205D02*
G03X31044Y364173I0J1969D01*
G01X0Y366142D02*
G03X3937Y362205I3937J0D01*
G01X31044Y364173D02*
Y387795D01*
G01X0Y566847D02*
Y366142D01*
G01X3937Y362205D02*
X29075D01*
G01X64567Y350394D02*
G03X60630Y354331I-3937J0D01*
G01X3937D02*
G03X0Y350394I0J-3937D01*
G01X60630Y354331D02*
X3937D01*
G01X44390Y393701D02*
G03I-2658J0D01*
G01X33012Y389764D02*
G03X31044Y387795I0J-1968D01*
G01X33012Y389764D02*
X199666D01*
G01X71407Y517570D02*
G03X76975Y523137I2784J2784D01*
G01X64567Y526040D02*
G03X65720Y523256I3938J0D01*
G01D02*
X94910Y494066D01*
G01X64567Y526040D02*
Y637713D01*
G01X-2692Y600283D02*
G03X0Y604019I-1245J3735D01*
G01Y566847D02*
G03X-2692Y570582I-3937J0D01*
G01X64567Y674885D02*
G03X67259Y671150I3937J0D01*
G01Y641448D02*
G03X64567Y637713I1245J-3735D01*
G01X73686Y669007D02*
X67259Y671150D01*
G01X64567Y674885D02*
Y738976D01*
G01X73686Y643591D02*
X67259Y641448D01*
G01X0Y738976D02*
Y604019D01*
G01X64567Y735039D02*
G03X72441I3937J0D01*
G01Y709842D02*
G03X64567I-3937J0D01*
G01Y738976D02*
G03X60630Y742913I-3937J0D01*
G01X3937D02*
G03X0Y738976I0J-3937D01*
G01X60630Y742913D02*
X3937D01*
G01X127362Y78740D02*
G03I-11023J0D01*
G01X118788Y137176D02*
G03I-4291J0D01*
G01X94791Y116738D02*
G03X89224Y111170I-2784J-2784D01*
G01X143454D02*
G03X137886Y116738I-2784J2784D01*
G01X134984Y104331D02*
G03X137768Y105484I0J3938D01*
G01X94910D02*
G03X97694Y104331I2784J2785D01*
G01X137886Y116738D02*
X133353Y112205D01*
G01X166957Y134673D02*
X137768Y105484D01*
G01X94791Y116738D02*
X99325Y112205D01*
G01X72441Y139088D02*
X76975Y134555D01*
G01X72441Y139088D02*
Y246293D01*
G01X133353Y112205D02*
X99325D01*
G01X134984Y104331D02*
X97694D01*
G01X84252Y276690D02*
G03X76175Y287895I-11811J0D01*
G01X76378Y276690D02*
G03X73686Y280425I-3937J0D01*
G01X76175Y247538D02*
G03X84252Y258743I-3734J11205D01*
G01X73686Y255008D02*
G03X76378Y258743I-1245J3735D01*
G01X76176Y287895D02*
X72441Y289140D01*
G01X84252Y258743D02*
Y276690D01*
G01X76378Y258743D02*
Y276690D01*
G01X72441Y289140D02*
Y321260D01*
G01X76176Y247538D02*
X72441Y246293D01*
G01X119874Y329366D02*
G03I-4291J0D01*
G01X76378Y354331D02*
G03X72441Y350394I0J-3937D01*
G01X76378Y354331D02*
X156299D01*
G01X72441Y346456D02*
Y350394D01*
G01X118788Y525759D02*
G03I-4291J0D01*
G01X94791Y505321D02*
G03X89224Y499753I-2784J-2784D01*
G01X143454D02*
G03X137886Y505321I-2784J2784D01*
G01D02*
X133353Y500787D01*
G01X94791Y505321D02*
X99325Y500787D01*
G01X72441Y527671D02*
X76975Y523137D01*
G01X133353Y500787D02*
X99325D01*
G01X134984Y492913D02*
G03X137768Y494066I0J3938D01*
G01X127362Y467323D02*
G03I-11023J0D01*
G01X94910Y494066D02*
G03X97694Y492913I2784J2785D01*
G01X166957Y523256D02*
X137768Y494066D01*
G01X134984Y492913D02*
X97694D01*
G01X72441Y527671D02*
Y634876D01*
G01X84252Y665272D02*
G03X76175Y676478I-11812J0D01*
G01Y636120D02*
G03X84252Y647326I-3735J11206D01*
G01X76176Y676477D02*
X72441Y677722D01*
G01X84252Y647326D02*
Y665272D01*
G01X72441Y677722D02*
Y709842D01*
G01X76176Y636121D02*
X72441Y634876D01*
G01X76378Y665272D02*
G03X73686Y669007I-3937J0D01*
G01Y643591D02*
G03X76378Y647326I-1245J3735D01*
G01D02*
Y665272D01*
G01X119874Y717948D02*
G03I-4291J0D01*
G01X76378Y742913D02*
G03X72441Y738976I0J-3937D01*
G01X76378Y742913D02*
X156299D01*
G01X72441Y735039D02*
Y738976D01*
G01X201634Y-24410D02*
G03X203603Y-26378I1968J0D01*
G01X201634Y-788D02*
Y-24410D01*
G01X203603Y-26378D02*
X228740D01*
G01X193603Y5118D02*
G03I-2658J0D01*
G01X201634Y-788D02*
G03X199666Y1181I-1969J0D01*
G01X155703Y134555D02*
G03X161271Y128987I2784J-2784D01*
G01X166957Y134673D02*
G03X168110Y137457I-2785J2784D01*
G01X160236Y139088D02*
X155703Y134555D01*
G01X160236Y246293D02*
Y139088D01*
G01X168110Y249131D02*
Y137457D01*
G01X165418Y282567D02*
G03X168110Y286302I-1245J3735D01*
G01X156502Y287895D02*
G03X148425Y276690I3734J-11205D01*
G01X158992Y280425D02*
G03X156299Y276690I1244J-3735D01*
G01X168110Y249131D02*
G03X165418Y252866I-3937J0D01*
G01X148425Y258743D02*
G03X156502Y247538I11811J0D01*
G01X156299Y258743D02*
G03X158992Y255008I3937J0D01*
G01X160236Y246293D02*
X156501Y247538D01*
G01X165418Y252866D02*
X158991Y255008D01*
G01X160236Y321260D02*
Y289140D01*
G01X168110Y350394D02*
Y286302D01*
G01X148425Y276690D02*
Y258743D01*
G01X156299Y276690D02*
Y258743D01*
G01X160236Y289140D02*
X156501Y287895D01*
G01X165418Y282567D02*
X158991Y280425D01*
G01X225227Y362205D02*
G03Y354331I0J-3937D01*
G01X207116D02*
G03Y362205I0J3937D01*
G01X160236Y346456D02*
G03X168110I3937J0D01*
G01Y321260D02*
G03X160236I-3937J0D01*
G01Y350394D02*
G03X156299Y354331I-3937J0D01*
G01X201634Y364173D02*
G03X203603Y362205I1968J0D01*
G01X201634Y387795D02*
Y364173D01*
G01X203603Y362205D02*
X228740D01*
G01X172047Y354331D02*
G03X168110Y350394I0J-3937D01*
G01X228740Y354331D02*
X172047D01*
G01X160236Y350394D02*
Y346456D01*
G01X193603Y393701D02*
G03I-2658J0D01*
G01X201634Y387795D02*
G03X199666Y389764I-1969J0D01*
G01X155703Y523137D02*
G03X161271Y517570I2784J-2783D01*
G01X160236Y527671D02*
X155703Y523137D01*
G01X166957Y523256D02*
G03X168110Y526040I-2785J2784D01*
G01Y637713D02*
Y526040D01*
G01X160236Y634876D02*
Y527671D01*
G01X156502Y676478D02*
G03X148425Y665272I3735J-11206D01*
G01Y647326D02*
G03X156502Y636120I11812J0D01*
G01X160236Y634876D02*
X156501Y636121D01*
G01X160236Y709842D02*
Y677722D01*
G01X148425Y665272D02*
Y647326D01*
G01X160236Y677722D02*
X156501Y676477D01*
G01X165418Y671150D02*
G03X168110Y674885I-1245J3735D01*
G01X158992Y669007D02*
G03X156299Y665272I1244J-3735D01*
G01X168110Y637713D02*
G03X165418Y641448I-3937J0D01*
G01X156299Y647326D02*
G03X158992Y643591I3937J0D01*
G01X165418Y641448D02*
X158991Y643591D01*
G01X168110Y738976D02*
Y674885D01*
G01X156299Y665272D02*
Y647326D01*
G01X165418Y671150D02*
X158991Y669007D01*
G01X160236Y735039D02*
G03X168110I3937J0D01*
G01Y709842D02*
G03X160236I-3937J0D01*
G01Y738976D02*
G03X156299Y742913I-3937J0D01*
G01X160236Y738976D02*
Y735039D01*
G01X172047Y742913D02*
G03X168110Y738976I0J-3937D01*
G01X228740Y742913D02*
X172047D01*
G01X236614Y-14567D02*
X244488D01*
G01X236614D02*
G03X232677Y-18504I0J-3937D01*
G01X248425D02*
G03X244488Y-14567I-3937J0D01*
G01X248425Y-22441D02*
G03X252362Y-26378I3937J0D01*
G01D02*
X309055D01*
G01X248425Y112921D02*
Y-22441D01*
G01X228740Y-26378D02*
G03X232677Y-22441I0J3937D01*
G01D02*
Y178669D01*
G01X236614Y16929D02*
X244488D01*
G01X232677Y20866D02*
G03X236614Y16929I3937J0D01*
G01X244488D02*
G03X248425Y20866I0J3937D01*
G01X246249Y145762D02*
G03X248425Y149283I-1761J3521D01*
G01Y112921D02*
G03X246249Y116442I-3937J0D01*
G01X242727Y144001D02*
G03X240551Y140480I1761J-3521D01*
G01Y121724D02*
G03X242727Y118203I3937J0D01*
G01X240551Y140480D02*
Y121724D01*
G01X242728Y118203D02*
X246249Y116442D01*
G01X242728Y144001D02*
X246249Y145762D01*
G01X248425Y350394D02*
Y149283D01*
G01X234853Y182190D02*
G03X232677Y178669I1761J-3521D01*
G01Y215031D02*
G03X234853Y211510I3937J0D01*
G01X238375Y183951D02*
G03X240551Y187472I-1761J3521D01*
G01Y206228D02*
G03X238375Y209749I-3937J0D01*
G01X240551Y187472D02*
Y206228D01*
G01X232677Y215031D02*
Y350394D01*
G01X238375Y209749D02*
X234854Y211510D01*
G01X238375Y183951D02*
X234854Y182190D01*
G01X273986Y362205D02*
G03Y354331I0J-3937D01*
G01X255876D02*
G03Y362205I0J3937D01*
G01X236614Y374016D02*
X244488D01*
G01X236614D02*
G03X232677Y370079I0J-3937D01*
G01X248425D02*
G03X244488Y374016I-3937J0D01*
G01X236614Y342519D02*
X244488D01*
G01X236614Y311023D02*
X244488D01*
G01X236614D02*
G03X232677Y307086I0J-3937D01*
G01Y346456D02*
G03X236614Y342519I3937J0D01*
G01X244488D02*
G03X248425Y346456I0J3937D01*
G01Y307086D02*
G03X244488Y311023I-3937J0D01*
G01X248425Y366142D02*
G03X252362Y362205I3937J0D01*
G01D02*
X309055D01*
G01X248425Y501504D02*
Y366142D01*
G01X228740Y362205D02*
G03X232677Y366142I0J3937D01*
G01D02*
Y567252D01*
G01X279469Y352362D02*
G03X277500Y354331I-1969J0D01*
G01X252362D02*
G03X248425Y350394I0J-3937D01*
G01X292815Y322834D02*
G03I-2657J0D01*
G01X279469Y328740D02*
G03X281437Y326771I1969J0D01*
G01X279469Y328740D02*
Y352362D01*
G01X448091Y326771D02*
X281437D01*
G01X277500Y354331D02*
X252362D01*
G01X232677Y350394D02*
G03X228740Y354331I-3937J0D01*
G01X236614Y405512D02*
X244488D01*
G01X232677Y409449D02*
G03X236614Y405512I3937J0D01*
G01X244488D02*
G03X248425Y409449I0J3937D01*
G01Y501504D02*
G03X246249Y505025I-3937J0D01*
G01X240551Y510307D02*
G03X242727Y506786I3937J0D01*
G01X240551Y529063D02*
Y510307D01*
G01X242728Y506786D02*
X246249Y505025D01*
G01Y534345D02*
G03X248425Y537866I-1761J3521D01*
G01X242727Y532584D02*
G03X240551Y529063I1761J-3521D01*
G01X248425Y738976D02*
Y537866D01*
G01X242728Y532584D02*
X246249Y534345D01*
G01X234853Y570773D02*
G03X232677Y567252I1761J-3521D01*
G01Y603614D02*
G03X234853Y600093I3937J0D01*
G01X238375Y572534D02*
G03X240551Y576055I-1761J3521D01*
G01Y594811D02*
G03X238375Y598332I-3937J0D01*
G01X240551Y576055D02*
Y594811D01*
G01X238375Y598332D02*
X234854Y600093D01*
G01X238375Y572534D02*
X234854Y570773D01*
G01X232677Y603614D02*
Y738976D01*
G01X236614Y731102D02*
X244488D01*
G01X236614Y699606D02*
X244488D01*
G01X236614D02*
G03X232677Y695669I0J-3937D01*
G01Y735039D02*
G03X236614Y731102I3937J0D01*
G01X244488D02*
G03X248425Y735039I0J3937D01*
G01Y695669D02*
G03X244488Y699606I-3937J0D01*
G01X279469Y740945D02*
G03X277500Y742913I-1968J0D01*
G01X252362D02*
G03X248425Y738976I0J-3937D01*
G01X292815Y711417D02*
G03I-2657J0D01*
G01X279469Y717323D02*
G03X281437Y715354I1969J0D01*
G01X279469Y717323D02*
Y740945D01*
G01X448091Y715354D02*
X281437D01*
G01X277500Y742913D02*
X252362D01*
G01X232677Y738976D02*
G03X228740Y742913I-3937J0D01*
G01X369811Y-1413D02*
G03I-4291J0D01*
G01X320866Y-18504D02*
G03X312992I-3937J0D01*
G01X320866Y-22441D02*
G03X324803Y-26378I3937J0D01*
G01X404725D02*
X324803D01*
G01X320866Y-22441D02*
Y-18504D01*
G01X309055Y-26378D02*
G03X312992Y-22441I0J3937D01*
G01D02*
Y41650D01*
G01Y6693D02*
G03X320866I3937J0D01*
G01X324600Y40057D02*
G03X332677Y51263I-3735J11206D01*
G01Y69209D02*
G03X324600Y80415I-11812J0D01*
G01X320866Y6693D02*
Y38813D01*
G01X332677Y51263D02*
Y69209D01*
G01X320866Y38813D02*
X324601Y40058D01*
G01X315685Y45385D02*
G03X312992Y41650I1244J-3735D01*
G01X322111Y47528D02*
G03X324803Y51263I-1245J3735D01*
G01Y69209D02*
G03X322111Y72944I-3937J0D01*
G01X324803Y51263D02*
Y69209D01*
G01X315684Y45385D02*
X322111Y47528D01*
G01X320866Y81659D02*
X324601Y80414D01*
G01X320866Y81659D02*
Y188864D01*
G01X312992Y78822D02*
G03X315685Y75087I3937J0D01*
G01X315684D02*
X322111Y72944D01*
G01X312992Y78822D02*
Y190495D01*
G01X370897Y190776D02*
G03I-4291J0D01*
G01X337649Y216782D02*
G03X343217Y211214I2784J-2784D01*
G01X325400Y193398D02*
G03X319832Y198965I-2784J2784D01*
G01X343217Y211214D02*
X347750Y215748D01*
G01X320866Y188864D02*
X325400Y193398D01*
G01X347750Y215748D02*
X381778D01*
G01X314145Y193279D02*
G03X312992Y190495I2785J-2784D01*
G01X346119Y223622D02*
G03X343335Y222469I0J-3938D01*
G01X314145Y193279D02*
X343335Y222469D01*
G01X375788Y249212D02*
G03I-11024J0D01*
G01X346119Y223622D02*
X383409D01*
G01X320866Y370079D02*
G03X312992I-3937J0D01*
G01X320866Y366142D02*
G03X324803Y362205I3937J0D01*
G01X404725D02*
X324803D01*
G01X320866Y366142D02*
Y370079D01*
G01X309055Y362205D02*
G03X312992Y366142I0J3937D01*
G01D02*
Y430233D01*
G01X369811Y387169D02*
G03I-4291J0D01*
G01X312992Y395275D02*
G03X320866I3937J0D01*
G01X324600Y428640D02*
G03X332677Y439845I-3734J11205D01*
G01X320866Y395275D02*
Y427395D01*
G01X332677Y439845D02*
Y457792D01*
G01X320866Y427395D02*
X324601Y428640D01*
G01X315685Y433968D02*
G03X312992Y430233I1244J-3735D01*
G01X322111Y436110D02*
G03X324803Y439845I-1245J3735D01*
G01D02*
Y457792D01*
G01X315684Y433968D02*
X322111Y436110D01*
G01X332677Y457792D02*
G03X324600Y468997I-11811J0D01*
G01X320866Y470242D02*
X324601Y468997D01*
G01X320866Y470242D02*
Y577447D01*
G01X312992Y467404D02*
G03X315685Y463669I3937J0D01*
G01X324803Y457792D02*
G03X322111Y461527I-3937J0D01*
G01X315684Y463669D02*
X322111Y461527D01*
G01X312992Y467404D02*
Y579078D01*
G01X370897Y579359D02*
G03I-4291J0D01*
G01X337649Y605365D02*
G03X343217Y599797I2784J-2784D01*
G01X325400Y581980D02*
G03X319832Y587548I-2784J2784D01*
G01X343217Y599797D02*
X347750Y604331D01*
G01X320866Y577447D02*
X325400Y581980D01*
G01X314145Y581862D02*
G03X312992Y579078I2785J-2784D01*
G01X314145Y581862D02*
X343335Y611051D01*
G01X347750Y604331D02*
X381778D01*
G01X346119Y612205D02*
G03X343335Y611051I1J-3937D01*
G01X375788Y637795D02*
G03I-11024J0D01*
G01X346119Y612205D02*
X383409D01*
G01X416536Y-18504D02*
G03X408662I-3937J0D01*
G01X404725Y-26378D02*
G03X408662Y-22441I0J3937D01*
G01Y-18504D02*
Y-22441D01*
G01X416536D02*
G03X420473Y-26378I3937J0D01*
G01D02*
X477166D01*
G01X416536Y41650D02*
Y-22441D01*
G01X408662Y6693D02*
G03X416536I3937J0D01*
G01X396851Y51263D02*
G03X404928Y40057I11812J0D01*
G01Y80415D02*
G03X396851Y69209I3735J-11206D01*
G01X404927Y40058D02*
X408662Y38813D01*
G01X396851Y69209D02*
Y51263D01*
G01X408662Y38813D02*
Y6693D01*
G01X416536Y41650D02*
G03X413843Y45385I-3937J0D01*
G01X404725Y51263D02*
G03X407417Y47528I3937J0D01*
G01Y72944D02*
G03X404725Y69209I1245J-3735D01*
G01X407417Y47528D02*
X413844Y45385D01*
G01X404725Y69209D02*
Y51263D01*
G01X408662Y188864D02*
Y81659D01*
G01X404927Y80414D02*
X408662Y81659D01*
G01X413843Y75087D02*
G03X416536Y78822I-1244J3735D01*
G01Y190495D02*
Y78822D01*
G01X407417Y72944D02*
X413844Y75087D01*
G01X409696Y198965D02*
G03X404128Y193398I-2784J-2783D01*
G01X386311Y211214D02*
G03X391879Y216782I2784J2784D01*
G01X386311Y211214D02*
X381778Y215748D01*
G01X408662Y188864D02*
X404128Y193398D01*
G01X386193Y222469D02*
G03X383409Y223622I-2784J-2785D01*
G01X416536Y190495D02*
G03X415383Y193279I-3938J0D01*
G01D02*
X386193Y222469D01*
G01X416536Y370079D02*
G03X408662I-3937J0D01*
G01X404725Y362205D02*
G03X408662Y366142I0J3937D01*
G01Y370079D02*
Y366142D01*
G01X416536D02*
G03X420473Y362205I3937J0D01*
G01D02*
X477166D01*
G01X416536Y430233D02*
Y366142D01*
G01X442028Y322834D02*
G03I-2658J0D01*
G01X448091Y326771D02*
G03X450059Y328740I0J1968D01*
G01X452028Y354331D02*
G03X450059Y352362I0J-1969D01*
G01D02*
Y328740D01*
G01X408662Y395275D02*
G03X416536I3937J0D01*
G01X396851Y439845D02*
G03X404928Y428640I11811J0D01*
G01X404927D02*
X408662Y427395D01*
G01X396851Y457792D02*
Y439845D01*
G01X408662Y427395D02*
Y395275D01*
G01X416536Y430233D02*
G03X413843Y433968I-3937J0D01*
G01X404725Y439845D02*
G03X407417Y436110I3937J0D01*
G01D02*
X413844Y433968D01*
G01X404725Y457792D02*
Y439845D01*
G01X404928Y468997D02*
G03X396851Y457792I3734J-11205D01*
G01X408662Y577447D02*
Y470242D01*
G01X404927Y468997D02*
X408662Y470242D01*
G01X413843Y463669D02*
G03X416536Y467404I-1244J3735D01*
G01X407417Y461527D02*
G03X404725Y457792I1245J-3735D01*
G01X416536Y579078D02*
Y467404D01*
G01X407417Y461527D02*
X413844Y463669D01*
G01X409696Y587548D02*
G03X404128Y581980I-2784J-2784D01*
G01X386311Y599797D02*
G03X391879Y605365I2784J2784D01*
G01X386311Y599797D02*
X381778Y604331D01*
G01X408662Y577447D02*
X404128Y581980D01*
G01X416536Y579078D02*
G03X415383Y581862I-3938J0D01*
G01D02*
X386193Y611051D01*
G01D02*
G03X383409Y612205I-2785J-2783D01*
G01X442028Y711417D02*
G03I-2658J0D01*
G01X448091Y715354D02*
G03X450059Y717323I0J1968D01*
G01X452028Y742913D02*
G03X450059Y740945I0J-1969D01*
G01D02*
Y717323D01*
G01X488977Y-22441D02*
G03X492914Y-26378I3937J0D01*
G01X497599D02*
G03X512599Y-11378I0J15000D01*
G01X488977Y-18504D02*
G03X481103I-3937J0D01*
G01X492914Y-26378D02*
X497599D01*
G01X512599Y-11378D02*
Y455139D01*
G01X488977Y-22441D02*
Y-18504D01*
G01X477166Y-26378D02*
G03X481103Y-22441I0J3937D01*
G01D02*
Y112517D01*
G01Y20866D02*
G03X488977I3937J0D01*
G01D02*
Y109679D01*
G01X492711Y110924D02*
G03X500788Y122129I-3734J11205D01*
G01Y140076D02*
G03X492711Y151281I-11811J0D01*
G01X488977Y109679D02*
X492712Y110924D01*
G01X500788Y122129D02*
Y140076D01*
G01X483795Y116252D02*
G03X481103Y112517I1245J-3735D01*
G01Y149688D02*
G03X483795Y145953I3937J0D01*
G01X490221Y118394D02*
G03X492914Y122129I-1244J3735D01*
G01Y140076D02*
G03X490221Y143811I-3937J0D01*
G01X483795Y145953D02*
X490222Y143811D01*
G01X483795Y116251D02*
X490222Y118394D01*
G01X492914Y122129D02*
Y140076D01*
G01X488977Y152525D02*
X492712Y151280D01*
G01X488977Y152525D02*
Y307086D01*
G01X481103Y149688D02*
Y350394D01*
G01X488977Y307086D02*
G03X481103I-3937J0D01*
G01Y346456D02*
G03X488977I3937J0D01*
G01Y370079D02*
G03X481103I-3937J0D01*
G01X488977Y346456D02*
Y370079D01*
G01X477166Y362205D02*
G03X481103Y366142I0J3937D01*
G01D02*
Y501099D01*
G01Y350394D02*
G03X477166Y354331I-3937J0D01*
G01D02*
X452028D01*
G01X481103Y409449D02*
G03X488977I3937J0D01*
G01D02*
Y498262D01*
G01X512599Y463013D02*
G03Y455139I0J-3937D01*
G01Y463013D02*
Y727913D01*
G01X492711Y499506D02*
G03X500788Y510711I-3734J11205D01*
G01X488977Y498262D02*
X492712Y499507D01*
G01X500788Y510711D02*
Y528658D01*
G01X483795Y504834D02*
G03X481103Y501099I1245J-3735D01*
G01X490221Y506976D02*
G03X492914Y510711I-1244J3735D01*
G01X483795Y504834D02*
X490222Y506976D01*
G01X492914Y510711D02*
Y528658D01*
G01X500788D02*
G03X492711Y539863I-11811J0D01*
G01X488977Y541108D02*
X492712Y539863D01*
G01X488977Y541108D02*
Y695669D01*
G01X481103Y538271D02*
G03X483795Y534535I3937J-1D01*
G01X492914Y528658D02*
G03X490221Y532393I-3937J0D01*
G01X483795Y534536D02*
X490222Y532393D01*
G01X481103Y538271D02*
Y738976D01*
G01X499107Y713716D02*
G03I-4291J0D01*
G01X492914Y742913D02*
G03X488977Y738976I0J-3937D01*
G01X512599Y727913D02*
G03X497599Y742913I-15000J0D01*
G01X488977Y695669D02*
G03X481103I-3937J0D01*
G01Y735039D02*
G03X488977I3937J0D01*
G01X492914Y742913D02*
X497599D01*
G01X488977Y735039D02*
Y738976D01*
G01X481103D02*
G03X477166Y742913I-3937J0D01*
G01D02*
X452028D01*
G54D15*
X48150Y45565D03*
Y47530D03*
Y49500D03*
Y51470D03*
Y53435D03*
X64450D03*
Y51470D03*
Y49500D03*
Y47530D03*
Y45565D03*
X190850Y34565D03*
Y36530D03*
Y38500D03*
Y40470D03*
Y42435D03*
X207150D03*
Y40470D03*
Y38500D03*
Y36530D03*
Y34565D03*
G54D51*
X191900Y115700D03*
X185900D03*
G54D42*
X22398Y154767D03*
G54D33*
X34342Y103542D03*
X57300Y118300D03*
X52618Y199384D03*
X109600Y51800D03*
X120100Y27400D03*
X218400Y115200D03*
G54D24*
X61000Y60500D03*
X14100Y48700D03*
X16813Y69474D03*
X51800Y38000D03*
X41300Y44400D03*
X56000Y60500D03*
X41300Y62600D03*
X49900Y16349D03*
X31600Y48100D03*
X29400Y58900D03*
X29650Y66500D03*
X67300Y38740D03*
X44416Y38922D03*
X66200Y60200D03*
X40631Y67104D03*
X71500Y53200D03*
X24900Y89600D03*
X12900Y107500D03*
X15800Y78400D03*
X16174Y73626D03*
X27042Y95162D03*
X45314Y102920D03*
X67282Y114234D03*
X69150Y105600D03*
X37000Y113300D03*
X41200Y95100D03*
X45900Y118700D03*
X55300Y165138D03*
X46000Y161800D03*
X17323Y159819D03*
X29232Y159877D03*
X49322Y183538D03*
X47699Y179634D03*
X12200Y201200D03*
X13646Y195250D03*
X11636Y227035D03*
X55800Y292900D03*
X43926Y277000D03*
X136400Y46500D03*
X77173Y23627D03*
X73400Y32000D03*
X145883Y54000D03*
X148558Y43046D03*
X75100Y68300D03*
X108300Y28700D03*
X112600D03*
X126100Y50300D03*
X121700D03*
X101800Y51800D03*
X116850Y34100D03*
X101200Y36500D03*
X129200Y27800D03*
X78600Y58500D03*
X75604Y76400D03*
X219082Y20786D03*
X178843Y62700D03*
X151336Y62300D03*
X193710Y20009D03*
X181167Y22264D03*
X172392Y18892D03*
X172328Y24231D03*
X205700Y55900D03*
X201600Y57100D03*
X161500Y65600D03*
X154424Y40024D03*
X183300Y54700D03*
X197500Y48750D03*
X178700Y52500D03*
X177637Y34565D03*
X192366Y61922D03*
X217732Y42900D03*
X223378Y30635D03*
X211300Y56100D03*
X214033Y44990D03*
X180600Y88400D03*
X165206Y110272D03*
X175766Y121643D03*
X164700Y82300D03*
X162610Y75430D03*
X171900Y105000D03*
X215000Y122900D03*
X182800Y92100D03*
X180800Y114300D03*
X223900Y203200D03*
X181800Y159400D03*
X215600Y151200D03*
X206763Y165082D03*
X218534Y202560D03*
X216100Y190400D03*
X211900Y182300D03*
X201900Y182100D03*
X207400Y182300D03*
X170617Y271803D03*
X220891Y296541D03*
X213762Y241107D03*
G54D34*
X15900Y82800D03*
X39900Y80500D03*
X100900Y40600D03*
X132600Y34100D03*
Y47000D03*
X176300Y40400D03*
X183500Y39700D03*
X168966Y83430D03*
G54D25*
X51750Y113060D03*
Y110500D03*
Y107940D03*
X58250D03*
Y113060D03*
X163452Y40642D03*
Y38082D03*
Y35522D03*
X169952D03*
Y40642D03*
X170750Y54440D03*
Y57000D03*
Y59560D03*
X164250D03*
Y54440D03*
X203050Y108060D03*
Y105500D03*
Y102940D03*
X209550D03*
Y108060D03*
G54D43*
X16798Y154767D03*
G54D52*
X215520Y140700D03*
G54D16*
X33500Y62600D03*
X48300Y59700D03*
X29700Y70800D03*
X70100Y60500D03*
X37331Y70804D03*
X38042Y109358D03*
X44800Y191610D03*
X30300Y284000D03*
X122300Y54000D03*
X97601Y32537D03*
X116600Y23500D03*
X184800Y70200D03*
X169487Y70136D03*
X198520Y113600D03*
X192771Y121500D03*
X215700Y185300D03*
G54D35*
X15900Y86400D03*
X39900Y84100D03*
X100900Y44200D03*
X132600Y37700D03*
Y50600D03*
X176300Y44000D03*
X183500Y43300D03*
X168966Y87030D03*
G54D26*
X17700Y106250D03*
Y112250D03*
X15300Y288650D03*
Y282650D03*
X222189Y316231D03*
Y310231D03*
G54D53*
X215520Y146300D03*
G54D17*
X36900Y62600D03*
X51700Y59700D03*
X33100Y70800D03*
X40731Y70804D03*
X41442Y109358D03*
X48200Y191610D03*
X33700Y284000D03*
X125700Y54000D03*
X101001Y32537D03*
X120000Y23500D03*
X73500Y60500D03*
X188200Y70200D03*
X172887Y70136D03*
X201920Y113600D03*
X196171Y121500D03*
X219100Y185300D03*
G54D44*
X7985Y222487D03*
G54D18*
X25600Y70800D03*
X36931Y66704D03*
X56700Y32300D03*
X41700Y118500D03*
X39200Y91400D03*
X48200Y187610D03*
Y195610D03*
X50862Y154167D03*
X111600Y24900D03*
X133400Y24000D03*
X79100Y47000D03*
X180700Y70200D03*
X174300Y48800D03*
X220682Y49139D03*
X192200Y90000D03*
X218300Y119000D03*
X219100Y181300D03*
Y197300D03*
X217800Y206700D03*
X210567Y283448D03*
G54D54*
X178720Y276481D03*
X186320D03*
G54D45*
X25000Y277000D03*
X36000D03*
X213790Y276128D03*
X202790D03*
G54D36*
X47933Y128937D03*
X16633D03*
X47933Y146653D03*
X16633D03*
X208170Y128937D03*
X176870D03*
X208170Y146653D03*
X176870D03*
G54D27*
X31500Y112222D03*
Y110252D03*
Y108282D03*
X29058D03*
Y110252D03*
Y112222D03*
X209976Y119370D03*
Y117400D03*
Y115430D03*
X207534D03*
Y117400D03*
Y119370D03*
G54D19*
X22200Y70800D03*
X33531Y66704D03*
X53300Y32300D03*
X38300Y118500D03*
X35800Y91400D03*
X44800Y187610D03*
Y195610D03*
X47462Y154167D03*
X108200Y24900D03*
X130000Y24000D03*
X75700Y47000D03*
X177300Y70200D03*
X170900Y48800D03*
X217282Y49139D03*
X188800Y90000D03*
X214900Y119000D03*
X215700Y181300D03*
Y197300D03*
X214400Y206700D03*
X207167Y283448D03*
G54D55*
X186454Y288824D03*
X191054D03*
X195654D03*
G54D28*
X33700Y118100D03*
X12100Y81300D03*
X28200Y117900D03*
X7200Y199300D03*
X9050Y191800D03*
X48300Y172100D03*
X54492Y181924D03*
X76500Y51200D03*
X80600D03*
X79200Y70100D03*
Y62600D03*
X79604Y80369D03*
X188250Y59096D03*
X222500Y38800D03*
X219378Y25905D03*
X205500Y48800D03*
X215300Y53200D03*
X201500Y48800D03*
X218832Y124859D03*
X168936Y76013D03*
X205500Y172700D03*
X209900D03*
G54D46*
X11103Y232047D03*
Y239647D03*
G54D37*
X16538Y173177D03*
X12600D03*
X16538Y167477D03*
X14569D03*
X12600D03*
X217790Y221230D03*
X215821D03*
X213852D03*
X217790Y226930D03*
X213852D03*
G54D29*
X33700Y121500D03*
X12100Y84700D03*
X28200Y121300D03*
X7200Y202700D03*
X9050Y195200D03*
X48300Y175500D03*
X54492Y185324D03*
X76500Y54600D03*
X80600D03*
X79200Y66000D03*
Y73500D03*
X79604Y83769D03*
X188250Y62496D03*
X222500Y42200D03*
X219378Y29305D03*
X205500Y52200D03*
X215300Y56600D03*
X201500Y52200D03*
X218832Y128259D03*
X168936Y79413D03*
X205500Y176100D03*
X209900D03*
G54D38*
X33809Y159738D03*
X6797Y255079D03*
Y250327D03*
X6793Y245566D03*
X188783Y156500D03*
G54D47*
X7985Y225487D03*
G54D56*
X186454Y283224D03*
X191054D03*
X195654D03*
G54D48*
X106048Y44885D03*
X108018D03*
X109988D03*
X111958D03*
Y35685D03*
X109988D03*
X108018D03*
X106048D03*
X127770Y34391D03*
X125800D03*
X123830D03*
X121860D03*
Y43591D03*
X123830D03*
X125800D03*
X127770D03*
G54D57*
X178741Y282699D03*
G54D39*
X39409Y159738D03*
X12397Y255079D03*
Y250327D03*
X12393Y245566D03*
X194383Y156500D03*
G54D58*
X178741Y285699D03*
G54D49*
X105788Y6299D03*
X102638D03*
X99489D03*
X96339D03*
X93189D03*
X90040D03*
X86890D03*
G54D59*
G01X-351984Y-328833D02*
X-383984D01*
G01X-351984Y-344833D02*
Y-424833D01*
G01D02*
X998716D01*
G01X-355984Y-328833D02*
G02I-12000J0D01*
G01X-361134D02*
G02I-6850J0D01*
G01X-367984Y-344833D02*
Y-312833D01*
G01X-351984Y-344833D02*
X998716D01*
G01X-351984Y-380333D02*
X998716D01*
G01X211216Y-344833D02*
Y-424833D01*
G01X348716Y-344833D02*
Y-424833D01*
G01X463716Y-344833D02*
Y-424833D01*
G01X631216Y-344833D02*
Y-424833D01*
G01X801216Y-344833D02*
Y-424833D01*
G01X998716Y-344833D02*
Y-424833D01*
G01X1026716Y-328833D02*
G02I-12000J0D01*
G01X1021566D02*
G02I-6850J0D01*
G01X1014716Y-344833D02*
Y-312833D01*
G01X1030716Y-328833D02*
X998716D01*
M02*
